G04 ================== begin FILE IDENTIFICATION RECORD ==================*
G04 Layout Name:  D:/<user>/Wistron_project/16317-1/gbr/16317-1.brd*
G04 Film Name:    DP_REF_L6*
G04 File Format:  Gerber RS274X*
G04 File Origin:  Cadence Allegro 16.5-S056*
G04 Origin Date:  Fri Jun 09 15:54:04 2017*
G04 *
G04 Layer:  BOARD GEOMETRY/DP_REF_L6_TBL*
G04 Layer:  BOARD GEOMETRY/DP_REF_L6_L6*
G04 Layer:  BOARD GEOMETRY/PANEL_OUTLINE*
G04 *
G04 Offset:    (0.00 0.00)*
G04 Mirror:    No*
G04 Mode:      Positive*
G04 Rotation:  0*
G04 FullContactRelief:  No*
G04 UndefLineWidth:     6.00*
G04 ================== end FILE IDENTIFICATION RECORD ====================*
%FSLAX35Y35*MOIN*%
%IR0*IPPOS*OFA0.00000B0.00000*MIA0B0*SFA1.00000B1.00000*%
%ADD10C,.02*%
%ADD11C,.006*%
%ADD12C,.0055*%
%ADD13C,.00475*%
G75*
%LPD*%
G75*
G54D10*
G01X1985143Y1416035D02*
X2790143D01*
G01X1985143Y1381385D02*
X2790143D01*
G01X1985143Y1485335D02*
Y1381385D01*
G01Y1485335D02*
X2790143D01*
G01X1985143Y1450685D02*
X2790143D01*
G01X2160143Y1485335D02*
Y1381385D01*
G01X2475143Y1485335D02*
Y1381385D01*
G01X2580143Y1485335D02*
Y1381385D01*
G01X2790143Y1485335D02*
Y1381385D01*
G54D11*
G01X6250Y-33194D02*
Y-50694D01*
G01X1228Y-33194D02*
X11272D01*
G01X20038Y-50694D02*
Y-33194D01*
G01Y-41652D02*
X21130Y-40194D01*
X22222Y-39319D01*
X23968Y-39028D01*
X25278Y-39319D01*
X26807Y-40486D01*
X27462Y-42236D01*
Y-50694D01*
G01X41250Y-39028D02*
Y-50694D01*
G01Y-34361D02*
X40813Y-34069D01*
Y-33486D01*
X41250Y-33194D01*
X41687Y-33486D01*
Y-34069D01*
X41250Y-34361D01*
G01X55475Y-48653D02*
X56567Y-49819D01*
X58095Y-50694D01*
X59405D01*
X60715Y-50111D01*
X61588Y-49236D01*
X62025Y-48070D01*
X61807Y-46319D01*
X60933Y-45444D01*
X57003Y-43694D01*
X56130Y-41652D01*
X56567Y-40194D01*
X57440Y-39319D01*
X58750Y-39028D01*
X60060Y-39319D01*
X61370Y-40194D01*
G01X90693Y-55069D02*
X92222Y-56236D01*
X93968Y-56527D01*
X95496Y-56236D01*
X96807Y-54778D01*
X97680Y-52736D01*
Y-39028D01*
G01Y-41361D02*
X96807Y-40194D01*
X95496Y-39319D01*
X93968Y-39028D01*
X92222Y-39611D01*
X91130Y-40777D01*
X90256Y-42819D01*
X89820Y-44861D01*
X90038Y-46611D01*
X90912Y-48653D01*
X92222Y-50111D01*
X93968Y-50694D01*
X95278Y-50402D01*
X96807Y-49236D01*
X97680Y-48070D01*
G01X107975Y-42819D02*
X114962D01*
X114307Y-40777D01*
X113215Y-39611D01*
X111687Y-39028D01*
X110158Y-39319D01*
X108848Y-40194D01*
X107975Y-42236D01*
X107538Y-43986D01*
Y-45736D01*
X107975Y-47486D01*
X109067Y-49236D01*
X110377Y-50402D01*
X111905Y-50694D01*
X113433Y-50111D01*
X114962Y-48361D01*
G01X125693Y-50694D02*
Y-39028D01*
G01Y-41361D02*
X126785Y-40194D01*
X127877Y-39319D01*
X129405Y-39028D01*
X130496Y-39319D01*
X131807Y-40194D01*
G01X142320Y-50694D02*
Y-33194D01*
G01Y-41944D02*
X143412Y-40194D01*
X144722Y-39319D01*
X146032Y-39028D01*
X147996Y-39611D01*
X149307Y-40777D01*
X150180Y-42819D01*
Y-45152D01*
X149743Y-47486D01*
X148870Y-49236D01*
X147342Y-50402D01*
X146032Y-50694D01*
X144722Y-50402D01*
X143412Y-49528D01*
X142320Y-48070D01*
G01X160475Y-42819D02*
X167462D01*
X166807Y-40777D01*
X165715Y-39611D01*
X164187Y-39028D01*
X162658Y-39319D01*
X161348Y-40194D01*
X160475Y-42236D01*
X160038Y-43986D01*
Y-45736D01*
X160475Y-47486D01*
X161567Y-49236D01*
X162877Y-50402D01*
X164405Y-50694D01*
X165933Y-50111D01*
X167462Y-48361D01*
G01X178193Y-50694D02*
Y-39028D01*
G01Y-41361D02*
X179285Y-40194D01*
X180377Y-39319D01*
X181905Y-39028D01*
X182996Y-39319D01*
X184307Y-40194D01*
G01X216250Y-39028D02*
Y-50694D01*
G01Y-34361D02*
X215813Y-34069D01*
Y-33486D01*
X216250Y-33194D01*
X216687Y-33486D01*
Y-34069D01*
X216250Y-34361D01*
G01X230475Y-48653D02*
X231567Y-49819D01*
X233095Y-50694D01*
X234405D01*
X235715Y-50111D01*
X236588Y-49236D01*
X237025Y-48070D01*
X236807Y-46319D01*
X235933Y-45444D01*
X232003Y-43694D01*
X231130Y-41652D01*
X231567Y-40194D01*
X232440Y-39319D01*
X233750Y-39028D01*
X235060Y-39319D01*
X236370Y-40194D01*
G01X265256Y-55069D02*
X266785Y-56236D01*
X268095Y-56527D01*
X269842Y-55944D01*
X271152Y-54486D01*
X271807Y-51860D01*
Y-39028D01*
G01Y-34361D02*
X271370Y-34069D01*
Y-33486D01*
X271807Y-33194D01*
X272243Y-33486D01*
Y-34069D01*
X271807Y-34361D01*
G01X282538Y-39028D02*
Y-47194D01*
X283412Y-49236D01*
X284722Y-50402D01*
X286250Y-50694D01*
X287778Y-50402D01*
X289088Y-49236D01*
X289962Y-47194D01*
G01Y-50694D02*
Y-39028D01*
G01X300475Y-48653D02*
X301567Y-49819D01*
X303095Y-50694D01*
X304405D01*
X305715Y-50111D01*
X306588Y-49236D01*
X307025Y-48070D01*
X306807Y-46319D01*
X305933Y-45444D01*
X302003Y-43694D01*
X301130Y-41652D01*
X301567Y-40194D01*
X302440Y-39319D01*
X303750Y-39028D01*
X305060Y-39319D01*
X306370Y-40194D01*
G01X321250Y-33194D02*
Y-50694D01*
G01X318193Y-39028D02*
X324307D01*
G01X354940Y-50694D02*
Y-35819D01*
X355377Y-34361D01*
X356250Y-33486D01*
X357560Y-33194D01*
X358870Y-33777D01*
X359525Y-35236D01*
G01X356905Y-40194D02*
X352538D01*
G01X373750Y-50694D02*
X372440Y-50402D01*
X371130Y-49236D01*
X370256Y-47194D01*
X369820Y-44861D01*
X370256Y-42527D01*
X371130Y-40486D01*
X372440Y-39319D01*
X373750Y-39028D01*
X375060Y-39319D01*
X376370Y-40486D01*
X377243Y-42527D01*
X377462Y-44861D01*
X377243Y-47194D01*
X376370Y-49236D01*
X375060Y-50402D01*
X373750Y-50694D01*
G01X388193D02*
Y-39028D01*
G01Y-41361D02*
X389285Y-40194D01*
X390377Y-39319D01*
X391905Y-39028D01*
X392996Y-39319D01*
X394307Y-40194D01*
G01X421665Y-55944D02*
X422975Y-56527D01*
X424722Y-55944D01*
X425813Y-54778D01*
X426687Y-53319D01*
X427996Y-48653D01*
X430835Y-39028D01*
G01X423848D02*
X427996Y-48653D01*
G01X443750Y-50694D02*
X442440Y-50402D01*
X441130Y-49236D01*
X440256Y-47194D01*
X439820Y-44861D01*
X440256Y-42527D01*
X441130Y-40486D01*
X442440Y-39319D01*
X443750Y-39028D01*
X445060Y-39319D01*
X446370Y-40486D01*
X447243Y-42527D01*
X447462Y-44861D01*
X447243Y-47194D01*
X446370Y-49236D01*
X445060Y-50402D01*
X443750Y-50694D01*
G01X457538Y-39028D02*
Y-47194D01*
X458412Y-49236D01*
X459722Y-50402D01*
X461250Y-50694D01*
X462778Y-50402D01*
X464088Y-49236D01*
X464962Y-47194D01*
G01Y-50694D02*
Y-39028D01*
G01X475693Y-50694D02*
Y-39028D01*
G01Y-41361D02*
X476785Y-40194D01*
X477877Y-39319D01*
X479405Y-39028D01*
X480496Y-39319D01*
X481807Y-40194D01*
G01X510693Y-50694D02*
Y-39028D01*
G01Y-41361D02*
X511785Y-40194D01*
X512877Y-39319D01*
X514405Y-39028D01*
X515496Y-39319D01*
X516807Y-40194D01*
G01X527975Y-42819D02*
X534962D01*
X534307Y-40777D01*
X533215Y-39611D01*
X531687Y-39028D01*
X530158Y-39319D01*
X528848Y-40194D01*
X527975Y-42236D01*
X527538Y-43986D01*
Y-45736D01*
X527975Y-47486D01*
X529067Y-49236D01*
X530377Y-50402D01*
X531905Y-50694D01*
X533433Y-50111D01*
X534962Y-48361D01*
G01X547440Y-50694D02*
Y-35819D01*
X547877Y-34361D01*
X548750Y-33486D01*
X550060Y-33194D01*
X551370Y-33777D01*
X552025Y-35236D01*
G01X549405Y-40194D02*
X545038D01*
G01X562975Y-42819D02*
X569962D01*
X569307Y-40777D01*
X568215Y-39611D01*
X566687Y-39028D01*
X565158Y-39319D01*
X563848Y-40194D01*
X562975Y-42236D01*
X562538Y-43986D01*
Y-45736D01*
X562975Y-47486D01*
X564067Y-49236D01*
X565377Y-50402D01*
X566905Y-50694D01*
X568433Y-50111D01*
X569962Y-48361D01*
G01X580693Y-50694D02*
Y-39028D01*
G01Y-41361D02*
X581785Y-40194D01*
X582877Y-39319D01*
X584405Y-39028D01*
X585496Y-39319D01*
X586807Y-40194D01*
G01X597975Y-42819D02*
X604962D01*
X604307Y-40777D01*
X603215Y-39611D01*
X601687Y-39028D01*
X600158Y-39319D01*
X598848Y-40194D01*
X597975Y-42236D01*
X597538Y-43986D01*
Y-45736D01*
X597975Y-47486D01*
X599067Y-49236D01*
X600377Y-50402D01*
X601905Y-50694D01*
X603433Y-50111D01*
X604962Y-48361D01*
G01X615038Y-50694D02*
Y-39028D01*
G01Y-41944D02*
X615912Y-40486D01*
X617222Y-39319D01*
X618968Y-39028D01*
X620496Y-39319D01*
X621807Y-40486D01*
X622462Y-42527D01*
Y-50694D01*
G01X639743Y-40486D02*
X638215Y-39319D01*
X636905Y-39028D01*
X635158Y-39611D01*
X633848Y-40777D01*
X632975Y-42819D01*
X632756Y-44861D01*
X632975Y-46903D01*
X633848Y-48653D01*
X635158Y-50111D01*
X636905Y-50694D01*
X638433Y-50111D01*
X639743Y-48944D01*
G01X650475Y-42819D02*
X657462D01*
X656807Y-40777D01*
X655715Y-39611D01*
X654187Y-39028D01*
X652658Y-39319D01*
X651348Y-40194D01*
X650475Y-42236D01*
X650038Y-43986D01*
Y-45736D01*
X650475Y-47486D01*
X651567Y-49236D01*
X652877Y-50402D01*
X654405Y-50694D01*
X655933Y-50111D01*
X657462Y-48361D01*
G01X688750Y-33194D02*
Y-50694D01*
G01X685693Y-39028D02*
X691807D01*
G01X706250Y-50694D02*
X704940Y-50402D01*
X703630Y-49236D01*
X702756Y-47194D01*
X702320Y-44861D01*
X702756Y-42527D01*
X703630Y-40486D01*
X704940Y-39319D01*
X706250Y-39028D01*
X707560Y-39319D01*
X708870Y-40486D01*
X709743Y-42527D01*
X709962Y-44861D01*
X709743Y-47194D01*
X708870Y-49236D01*
X707560Y-50402D01*
X706250Y-50694D01*
G01X739940D02*
Y-35819D01*
X740377Y-34361D01*
X741250Y-33486D01*
X742560Y-33194D01*
X743870Y-33777D01*
X744525Y-35236D01*
G01X741905Y-40194D02*
X737538D01*
G01X758750Y-39028D02*
Y-50694D01*
G01Y-34361D02*
X758313Y-34069D01*
Y-33486D01*
X758750Y-33194D01*
X759187Y-33486D01*
Y-34069D01*
X758750Y-34361D01*
G01X772538Y-50694D02*
Y-39028D01*
G01Y-41944D02*
X773412Y-40486D01*
X774722Y-39319D01*
X776468Y-39028D01*
X777996Y-39319D01*
X779307Y-40486D01*
X779962Y-42527D01*
Y-50694D01*
G01X797680Y-33194D02*
Y-50694D01*
G01Y-48070D02*
X796807Y-49528D01*
X795496Y-50402D01*
X793968Y-50694D01*
X792222Y-50111D01*
X790912Y-48653D01*
X790038Y-46903D01*
X789820Y-44861D01*
X790038Y-42819D01*
X790912Y-41069D01*
X792222Y-39611D01*
X793968Y-39028D01*
X795496Y-39319D01*
X796588Y-39903D01*
X797680Y-41069D01*
G01X828750Y-33194D02*
Y-50694D01*
G01X825693Y-39028D02*
X831807D01*
G01X842538Y-50694D02*
Y-33194D01*
G01Y-41652D02*
X843630Y-40194D01*
X844722Y-39319D01*
X846468Y-39028D01*
X847778Y-39319D01*
X849307Y-40486D01*
X849962Y-42236D01*
Y-50694D01*
G01X860475Y-42819D02*
X867462D01*
X866807Y-40777D01*
X865715Y-39611D01*
X864187Y-39028D01*
X862658Y-39319D01*
X861348Y-40194D01*
X860475Y-42236D01*
X860038Y-43986D01*
Y-45736D01*
X860475Y-47486D01*
X861567Y-49236D01*
X862877Y-50402D01*
X864405Y-50694D01*
X865933Y-50111D01*
X867462Y-48361D01*
G01X893947Y-50694D02*
Y-33194D01*
X898313D01*
X900060Y-34069D01*
X901370Y-35236D01*
X902462Y-36985D01*
X903335Y-39028D01*
X903553Y-41944D01*
X903335Y-44861D01*
X902462Y-46903D01*
X901370Y-48653D01*
X900060Y-49819D01*
X898313Y-50694D01*
X893947D01*
G01X911883D02*
Y-33194D01*
X917123D01*
X918870Y-34069D01*
X920180Y-36111D01*
X920617Y-38444D01*
X920180Y-40777D01*
X919088Y-42527D01*
X917123Y-43403D01*
X911883D01*
G01X951250Y-39028D02*
Y-50694D01*
G01Y-34361D02*
X950813Y-34069D01*
Y-33486D01*
X951250Y-33194D01*
X951687Y-33486D01*
Y-34069D01*
X951250Y-34361D01*
G01X962200Y-50694D02*
Y-39028D01*
G01Y-42236D02*
X962855Y-40777D01*
X963947Y-39611D01*
X965475Y-39028D01*
X967003Y-39611D01*
X968095Y-40777D01*
X968750Y-42236D01*
Y-50694D01*
G01Y-42236D02*
X969405Y-40777D01*
X970496Y-39611D01*
X972025Y-39028D01*
X973553Y-39611D01*
X974645Y-40777D01*
X975300Y-42527D01*
Y-50694D01*
G01X982320Y-56527D02*
Y-39028D01*
G01Y-41652D02*
X983412Y-40194D01*
X984503Y-39319D01*
X986250Y-39028D01*
X987778Y-39319D01*
X989307Y-40777D01*
X989962Y-42819D01*
X990180Y-44861D01*
X989962Y-46903D01*
X989307Y-48944D01*
X987996Y-50111D01*
X986250Y-50694D01*
X984722Y-50402D01*
X983193Y-49528D01*
X982320Y-48361D01*
G01X1000475Y-42819D02*
X1007462D01*
X1006807Y-40777D01*
X1005715Y-39611D01*
X1004187Y-39028D01*
X1002658Y-39319D01*
X1001348Y-40194D01*
X1000475Y-42236D01*
X1000038Y-43986D01*
Y-45736D01*
X1000475Y-47486D01*
X1001567Y-49236D01*
X1002877Y-50402D01*
X1004405Y-50694D01*
X1005933Y-50111D01*
X1007462Y-48361D01*
G01X1025180Y-33194D02*
Y-50694D01*
G01Y-48070D02*
X1024307Y-49528D01*
X1022996Y-50402D01*
X1021468Y-50694D01*
X1019722Y-50111D01*
X1018412Y-48653D01*
X1017538Y-46903D01*
X1017320Y-44861D01*
X1017538Y-42819D01*
X1018412Y-41069D01*
X1019722Y-39611D01*
X1021468Y-39028D01*
X1022996Y-39319D01*
X1024088Y-39903D01*
X1025180Y-41069D01*
G01X1042680Y-50694D02*
Y-39028D01*
G01Y-41069D02*
X1041807Y-39903D01*
X1040496Y-39319D01*
X1038968Y-39028D01*
X1037440Y-39611D01*
X1036130Y-40777D01*
X1035256Y-42527D01*
X1034820Y-44861D01*
X1035256Y-47194D01*
X1036130Y-48944D01*
X1037440Y-50111D01*
X1038968Y-50694D01*
X1040496Y-50402D01*
X1041807Y-49528D01*
X1042680Y-48361D01*
G01X1052538Y-50694D02*
Y-39028D01*
G01Y-41944D02*
X1053412Y-40486D01*
X1054722Y-39319D01*
X1056468Y-39028D01*
X1057996Y-39319D01*
X1059307Y-40486D01*
X1059962Y-42527D01*
Y-50694D01*
G01X1077243Y-40486D02*
X1075715Y-39319D01*
X1074405Y-39028D01*
X1072658Y-39611D01*
X1071348Y-40777D01*
X1070475Y-42819D01*
X1070256Y-44861D01*
X1070475Y-46903D01*
X1071348Y-48653D01*
X1072658Y-50111D01*
X1074405Y-50694D01*
X1075933Y-50111D01*
X1077243Y-48944D01*
G01X1087975Y-42819D02*
X1094962D01*
X1094307Y-40777D01*
X1093215Y-39611D01*
X1091687Y-39028D01*
X1090158Y-39319D01*
X1088848Y-40194D01*
X1087975Y-42236D01*
X1087538Y-43986D01*
Y-45736D01*
X1087975Y-47486D01*
X1089067Y-49236D01*
X1090377Y-50402D01*
X1091905Y-50694D01*
X1093433Y-50111D01*
X1094962Y-48361D01*
G01X1126250Y-33194D02*
Y-50694D01*
G01X1123193Y-39028D02*
X1129307D01*
G01X1140693Y-50694D02*
Y-39028D01*
G01Y-41361D02*
X1141785Y-40194D01*
X1142877Y-39319D01*
X1144405Y-39028D01*
X1145496Y-39319D01*
X1146807Y-40194D01*
G01X1165180Y-50694D02*
Y-39028D01*
G01Y-41069D02*
X1164307Y-39903D01*
X1162996Y-39319D01*
X1161468Y-39028D01*
X1159940Y-39611D01*
X1158630Y-40777D01*
X1157756Y-42527D01*
X1157320Y-44861D01*
X1157756Y-47194D01*
X1158630Y-48944D01*
X1159940Y-50111D01*
X1161468Y-50694D01*
X1162996Y-50402D01*
X1164307Y-49528D01*
X1165180Y-48361D01*
G01X1182243Y-40486D02*
X1180715Y-39319D01*
X1179405Y-39028D01*
X1177658Y-39611D01*
X1176348Y-40777D01*
X1175475Y-42819D01*
X1175256Y-44861D01*
X1175475Y-46903D01*
X1176348Y-48653D01*
X1177658Y-50111D01*
X1179405Y-50694D01*
X1180933Y-50111D01*
X1182243Y-48944D01*
G01X1192975Y-42819D02*
X1199962D01*
X1199307Y-40777D01*
X1198215Y-39611D01*
X1196687Y-39028D01*
X1195158Y-39319D01*
X1193848Y-40194D01*
X1192975Y-42236D01*
X1192538Y-43986D01*
Y-45736D01*
X1192975Y-47486D01*
X1194067Y-49236D01*
X1195377Y-50402D01*
X1196905Y-50694D01*
X1198433Y-50111D01*
X1199962Y-48361D01*
G01X1210475Y-48653D02*
X1211567Y-49819D01*
X1213095Y-50694D01*
X1214405D01*
X1215715Y-50111D01*
X1216588Y-49236D01*
X1217025Y-48070D01*
X1216807Y-46319D01*
X1215933Y-45444D01*
X1212003Y-43694D01*
X1211130Y-41652D01*
X1211567Y-40194D01*
X1212440Y-39319D01*
X1213750Y-39028D01*
X1215060Y-39319D01*
X1216370Y-40194D01*
G01X1248750Y-39028D02*
Y-50694D01*
G01Y-34361D02*
X1248313Y-34069D01*
Y-33486D01*
X1248750Y-33194D01*
X1249187Y-33486D01*
Y-34069D01*
X1248750Y-34361D01*
G01X1262538Y-50694D02*
Y-39028D01*
G01Y-41944D02*
X1263412Y-40486D01*
X1264722Y-39319D01*
X1266468Y-39028D01*
X1267996Y-39319D01*
X1269307Y-40486D01*
X1269962Y-42527D01*
Y-50694D01*
G01X1301250D02*
Y-33194D01*
G01X1322680Y-50694D02*
Y-39028D01*
G01Y-41069D02*
X1321807Y-39903D01*
X1320496Y-39319D01*
X1318968Y-39028D01*
X1317440Y-39611D01*
X1316130Y-40777D01*
X1315256Y-42527D01*
X1314820Y-44861D01*
X1315256Y-47194D01*
X1316130Y-48944D01*
X1317440Y-50111D01*
X1318968Y-50694D01*
X1320496Y-50402D01*
X1321807Y-49528D01*
X1322680Y-48361D01*
G01X1331665Y-55944D02*
X1332975Y-56527D01*
X1334722Y-55944D01*
X1335813Y-54778D01*
X1336687Y-53319D01*
X1337996Y-48653D01*
X1340835Y-39028D01*
G01X1333848D02*
X1337996Y-48653D01*
G01X1350475Y-42819D02*
X1357462D01*
X1356807Y-40777D01*
X1355715Y-39611D01*
X1354187Y-39028D01*
X1352658Y-39319D01*
X1351348Y-40194D01*
X1350475Y-42236D01*
X1350038Y-43986D01*
Y-45736D01*
X1350475Y-47486D01*
X1351567Y-49236D01*
X1352877Y-50402D01*
X1354405Y-50694D01*
X1355933Y-50111D01*
X1357462Y-48361D01*
G01X1368193Y-50694D02*
Y-39028D01*
G01Y-41361D02*
X1369285Y-40194D01*
X1370377Y-39319D01*
X1371905Y-39028D01*
X1372996Y-39319D01*
X1374307Y-40194D01*
G01X1401883Y-33194D02*
Y-50694D01*
X1410617D01*
G01X1419602Y-43403D02*
X1421130Y-41361D01*
X1422440Y-40194D01*
X1424187Y-39611D01*
X1425715Y-40194D01*
X1426807Y-41361D01*
X1427680Y-43111D01*
X1427898Y-45152D01*
X1427680Y-46903D01*
X1426807Y-48653D01*
X1425496Y-50111D01*
X1423968Y-50694D01*
X1422222Y-50111D01*
X1420693Y-48361D01*
X1419820Y-45736D01*
X1419602Y-42819D01*
X1420038Y-39028D01*
X1420693Y-36985D01*
X1421785Y-34944D01*
X1423313Y-33486D01*
X1424842Y-33194D01*
X1426370Y-33777D01*
X1427462Y-35236D01*
G01X1441250Y-51277D02*
X1440813Y-50986D01*
Y-50402D01*
X1441250Y-50111D01*
X1441687Y-50402D01*
Y-50986D01*
X1441250Y-51277D01*
G01X1986890Y1495085D02*
Y1512585D01*
X1991256D01*
X1993003Y1511710D01*
X1994313Y1510543D01*
X1995405Y1508794D01*
X1996278Y1506751D01*
X1996496Y1503835D01*
X1996278Y1500918D01*
X1995405Y1498876D01*
X1994313Y1497126D01*
X1993003Y1495960D01*
X1991256Y1495085D01*
X1986890D01*
G01X2004826D02*
Y1512585D01*
X2010066D01*
X2011813Y1511710D01*
X2013123Y1509668D01*
X2013560Y1507335D01*
X2013123Y1505002D01*
X2012031Y1503252D01*
X2010066Y1502376D01*
X2004826D01*
G01X2041573Y1512585D02*
X2046813D01*
G01X2044193D02*
Y1495085D01*
G01X2041573D02*
X2046813D01*
G01X2056016D02*
Y1512585D01*
X2061693Y1498002D01*
X2067370Y1512585D01*
Y1495085D01*
G01X2074826D02*
Y1512585D01*
X2080066D01*
X2081813Y1511710D01*
X2083123Y1509668D01*
X2083560Y1507335D01*
X2083123Y1505002D01*
X2082031Y1503252D01*
X2080066Y1502376D01*
X2074826D01*
G01X2101060Y1495085D02*
X2092326D01*
Y1512585D01*
X2101060D01*
G01X2097566Y1504127D02*
X2092326D01*
G01X2109390Y1495085D02*
Y1512585D01*
X2113756D01*
X2115503Y1511710D01*
X2116813Y1510543D01*
X2117905Y1508794D01*
X2118778Y1506751D01*
X2118996Y1503835D01*
X2118778Y1500918D01*
X2117905Y1498876D01*
X2116813Y1497126D01*
X2115503Y1495960D01*
X2113756Y1495085D01*
X2109390D01*
G01X2126234D02*
X2131693Y1512585D01*
X2137152Y1495085D01*
G01X2135186Y1501210D02*
X2128199D01*
G01X2144171Y1495085D02*
Y1512585D01*
X2154215Y1495085D01*
Y1512585D01*
G01X2171496Y1511126D02*
X2170186Y1512002D01*
X2168658Y1512585D01*
X2166911D01*
X2164946Y1511710D01*
X2163418Y1510252D01*
X2162326Y1508501D01*
X2161453Y1505585D01*
X2161234Y1502960D01*
X2161671Y1500335D01*
X2162326Y1498585D01*
X2163636Y1496835D01*
X2165165Y1495668D01*
X2166693Y1495085D01*
X2168221D01*
X2169750Y1495668D01*
X2171060Y1496543D01*
X2172152Y1497709D01*
G01X2188560Y1495085D02*
X2179826D01*
Y1512585D01*
X2188560D01*
G01X2185066Y1504127D02*
X2179826D01*
G01X2219193Y1512585D02*
Y1495085D01*
G01X2214171Y1512585D02*
X2224215D01*
G01X2231234Y1495085D02*
X2236693Y1512585D01*
X2242152Y1495085D01*
G01X2240186Y1501210D02*
X2233199D01*
G01X2255939Y1504418D02*
X2256813Y1505293D01*
X2257468Y1506751D01*
X2257905Y1508794D01*
X2257468Y1510543D01*
X2256595Y1511710D01*
X2255066Y1512585D01*
X2249171D01*
Y1495085D01*
X2256376D01*
X2257905Y1496251D01*
X2258778Y1498002D01*
X2259215Y1500043D01*
X2258778Y1502085D01*
X2257468Y1503835D01*
X2255939Y1504418D01*
X2249171D01*
G01X2267326Y1512585D02*
Y1495085D01*
X2276060D01*
G01X2293560D02*
X2284826D01*
Y1512585D01*
X2293560D01*
G01X2290066Y1504127D02*
X2284826D01*
G01X2306693Y1494502D02*
X2306256Y1494793D01*
Y1495377D01*
X2306693Y1495668D01*
X2307130Y1495377D01*
Y1494793D01*
X2306693Y1494502D01*
G01Y1502376D02*
X2306256Y1502668D01*
Y1503252D01*
X2306693Y1503543D01*
X2307130Y1503252D01*
Y1502668D01*
X2306693Y1502376D01*
G01X2337326Y1512585D02*
Y1495085D01*
X2346060D01*
G01X2355045Y1502376D02*
X2356573Y1504418D01*
X2357883Y1505585D01*
X2359630Y1506168D01*
X2361158Y1505585D01*
X2362250Y1504418D01*
X2363123Y1502668D01*
X2363341Y1500627D01*
X2363123Y1498876D01*
X2362250Y1497126D01*
X2360939Y1495668D01*
X2359411Y1495085D01*
X2357665Y1495668D01*
X2356136Y1497418D01*
X2355263Y1500043D01*
X2355045Y1502960D01*
X2355481Y1506751D01*
X2356136Y1508794D01*
X2357228Y1510835D01*
X2358756Y1512293D01*
X2360285Y1512585D01*
X2361813Y1512002D01*
X2362905Y1510543D01*
G01X2008773Y1477935D02*
X2014013D01*
G01X2011393D02*
Y1460435D01*
G01X2008773D02*
X2014013D01*
G01X2023216D02*
Y1477935D01*
X2028893Y1463352D01*
X2034570Y1477935D01*
Y1460435D01*
G01X2042026D02*
Y1477935D01*
X2047266D01*
X2049013Y1477060D01*
X2050323Y1475018D01*
X2050760Y1472685D01*
X2050323Y1470352D01*
X2049231Y1468602D01*
X2047266Y1467726D01*
X2042026D01*
G01X2062801Y1454602D02*
X2060618Y1457518D01*
X2059526Y1460435D01*
Y1472101D01*
X2060618Y1475018D01*
X2062801Y1477935D01*
G01X2081393Y1460435D02*
X2079646Y1460727D01*
X2078118Y1461893D01*
X2076808Y1463643D01*
X2075934Y1465685D01*
X2075498Y1468018D01*
Y1470352D01*
X2075934Y1472685D01*
X2076808Y1474727D01*
X2078118Y1476476D01*
X2079646Y1477643D01*
X2081393Y1477935D01*
X2083139Y1477643D01*
X2084668Y1476476D01*
X2085978Y1474727D01*
X2086852Y1472685D01*
X2087288Y1470352D01*
Y1468018D01*
X2086852Y1465685D01*
X2085978Y1463643D01*
X2084668Y1461893D01*
X2083139Y1460727D01*
X2081393Y1460435D01*
G01X2095181D02*
Y1477935D01*
G01Y1469477D02*
X2096273Y1470935D01*
X2097365Y1471810D01*
X2099111Y1472101D01*
X2100421Y1471810D01*
X2101950Y1470643D01*
X2102605Y1468893D01*
Y1460435D01*
G01X2109843D02*
Y1472101D01*
G01Y1468893D02*
X2110498Y1470352D01*
X2111590Y1471518D01*
X2113118Y1472101D01*
X2114646Y1471518D01*
X2115738Y1470352D01*
X2116393Y1468893D01*
Y1460435D01*
G01Y1468893D02*
X2117048Y1470352D01*
X2118139Y1471518D01*
X2119668Y1472101D01*
X2121196Y1471518D01*
X2122288Y1470352D01*
X2122943Y1468602D01*
Y1460435D01*
G01X2134985Y1454602D02*
X2137168Y1457518D01*
X2138260Y1460435D01*
Y1472101D01*
X2137168Y1475018D01*
X2134985Y1477935D01*
G01X2046393Y1425785D02*
X2047921Y1426077D01*
X2049668Y1426951D01*
X2050760Y1428409D01*
X2051196Y1430452D01*
X2050760Y1432493D01*
X2049450Y1434243D01*
X2047485Y1435118D01*
X2045301D01*
X2043991Y1435702D01*
X2042899Y1437160D01*
X2042463Y1439201D01*
X2043118Y1441243D01*
X2044646Y1442702D01*
X2046393Y1443285D01*
X2048139Y1442702D01*
X2049668Y1441243D01*
X2050323Y1439201D01*
X2049886Y1437160D01*
X2048795Y1435702D01*
X2047485Y1435118D01*
X2045301D01*
X2043336Y1434243D01*
X2042026Y1432493D01*
X2041590Y1430452D01*
X2042026Y1428409D01*
X2043118Y1426951D01*
X2044865Y1426077D01*
X2046393Y1425785D01*
G01X2059090Y1428409D02*
X2060399Y1426951D01*
X2061928Y1426077D01*
X2063893Y1425785D01*
X2065858Y1426368D01*
X2067386Y1427535D01*
X2068478Y1429576D01*
X2068696Y1431910D01*
X2068260Y1434243D01*
X2067168Y1435702D01*
X2065639Y1436868D01*
X2064111Y1437160D01*
X2062583Y1436868D01*
X2060618Y1435702D01*
X2061273Y1443285D01*
X2067168D01*
G01X2081393Y1425202D02*
X2080956Y1425493D01*
Y1426077D01*
X2081393Y1426368D01*
X2081830Y1426077D01*
Y1425493D01*
X2081393Y1425202D01*
G01X2098893Y1443285D02*
X2097146Y1442702D01*
X2095836Y1441243D01*
X2094963Y1439494D01*
X2094308Y1437160D01*
X2094090Y1434535D01*
X2094308Y1431910D01*
X2094963Y1429576D01*
X2095836Y1427826D01*
X2097146Y1426368D01*
X2098893Y1425785D01*
X2100639Y1426368D01*
X2101950Y1427826D01*
X2102823Y1429576D01*
X2103478Y1431910D01*
X2103696Y1434535D01*
X2103478Y1437160D01*
X2102823Y1439494D01*
X2101950Y1441243D01*
X2100639Y1442702D01*
X2098893Y1443285D01*
G01X2037643Y1391135D02*
Y1408635D01*
X2035023Y1405135D01*
G01Y1391135D02*
X2040263D01*
G01X2055143Y1408635D02*
X2053396Y1408052D01*
X2052086Y1406593D01*
X2051213Y1404844D01*
X2050558Y1402510D01*
X2050340Y1399885D01*
X2050558Y1397260D01*
X2051213Y1394926D01*
X2052086Y1393176D01*
X2053396Y1391718D01*
X2055143Y1391135D01*
X2056889Y1391718D01*
X2058200Y1393176D01*
X2059073Y1394926D01*
X2059728Y1397260D01*
X2059946Y1399885D01*
X2059728Y1402510D01*
X2059073Y1404844D01*
X2058200Y1406593D01*
X2056889Y1408052D01*
X2055143Y1408635D01*
G01X2072643D02*
X2070896Y1408052D01*
X2069586Y1406593D01*
X2068713Y1404844D01*
X2068058Y1402510D01*
X2067840Y1399885D01*
X2068058Y1397260D01*
X2068713Y1394926D01*
X2069586Y1393176D01*
X2070896Y1391718D01*
X2072643Y1391135D01*
X2074389Y1391718D01*
X2075700Y1393176D01*
X2076573Y1394926D01*
X2077228Y1397260D01*
X2077446Y1399885D01*
X2077228Y1402510D01*
X2076573Y1404844D01*
X2075700Y1406593D01*
X2074389Y1408052D01*
X2072643Y1408635D01*
G01X2090143Y1390552D02*
X2089706Y1390843D01*
Y1391427D01*
X2090143Y1391718D01*
X2090580Y1391427D01*
Y1390843D01*
X2090143Y1390552D01*
G01X2107643Y1408635D02*
X2105896Y1408052D01*
X2104586Y1406593D01*
X2103713Y1404844D01*
X2103058Y1402510D01*
X2102840Y1399885D01*
X2103058Y1397260D01*
X2103713Y1394926D01*
X2104586Y1393176D01*
X2105896Y1391718D01*
X2107643Y1391135D01*
X2109389Y1391718D01*
X2110700Y1393176D01*
X2111573Y1394926D01*
X2112228Y1397260D01*
X2112446Y1399885D01*
X2112228Y1402510D01*
X2111573Y1404844D01*
X2110700Y1406593D01*
X2109389Y1408052D01*
X2107643Y1408635D01*
G01X2260340Y1428409D02*
X2261649Y1426951D01*
X2263178Y1426077D01*
X2265143Y1425785D01*
X2267108Y1426368D01*
X2268636Y1427535D01*
X2269728Y1429576D01*
X2269946Y1431910D01*
X2269510Y1434243D01*
X2268418Y1435702D01*
X2266889Y1436868D01*
X2265361Y1437160D01*
X2263833Y1436868D01*
X2261868Y1435702D01*
X2262523Y1443285D01*
X2268418D01*
G01X2282643Y1425202D02*
X2282206Y1425493D01*
Y1426077D01*
X2282643Y1426368D01*
X2283080Y1426077D01*
Y1425493D01*
X2282643Y1425202D01*
G01X2295340Y1428409D02*
X2296649Y1426951D01*
X2298178Y1426077D01*
X2300143Y1425785D01*
X2302108Y1426368D01*
X2303636Y1427535D01*
X2304728Y1429576D01*
X2304946Y1431910D01*
X2304510Y1434243D01*
X2303418Y1435702D01*
X2301889Y1436868D01*
X2300361Y1437160D01*
X2298833Y1436868D01*
X2296868Y1435702D01*
X2297523Y1443285D01*
X2303418D01*
G01X2313713Y1425202D02*
X2321573Y1443285D01*
G01X2330995Y1433076D02*
X2332523Y1435118D01*
X2333833Y1436285D01*
X2335580Y1436868D01*
X2337108Y1436285D01*
X2338200Y1435118D01*
X2339073Y1433368D01*
X2339291Y1431327D01*
X2339073Y1429576D01*
X2338200Y1427826D01*
X2336889Y1426368D01*
X2335361Y1425785D01*
X2333615Y1426368D01*
X2332086Y1428118D01*
X2331213Y1430743D01*
X2330995Y1433660D01*
X2331431Y1437451D01*
X2332086Y1439494D01*
X2333178Y1441535D01*
X2334706Y1442993D01*
X2336235Y1443285D01*
X2337763Y1442702D01*
X2338855Y1441243D01*
G01X2352643Y1425202D02*
X2352206Y1425493D01*
Y1426077D01*
X2352643Y1426368D01*
X2353080Y1426077D01*
Y1425493D01*
X2352643Y1425202D01*
G01X2370143Y1443285D02*
X2368396Y1442702D01*
X2367086Y1441243D01*
X2366213Y1439494D01*
X2365558Y1437160D01*
X2365340Y1434535D01*
X2365558Y1431910D01*
X2366213Y1429576D01*
X2367086Y1427826D01*
X2368396Y1426368D01*
X2370143Y1425785D01*
X2371889Y1426368D01*
X2373200Y1427826D01*
X2374073Y1429576D01*
X2374728Y1431910D01*
X2374946Y1434535D01*
X2374728Y1437160D01*
X2374073Y1439494D01*
X2373200Y1441243D01*
X2371889Y1442702D01*
X2370143Y1443285D01*
G01X2259013Y1391135D02*
Y1408635D01*
X2250934Y1396093D01*
X2261852D01*
G01X2273893Y1390552D02*
X2273456Y1390843D01*
Y1391427D01*
X2273893Y1391718D01*
X2274330Y1391427D01*
Y1390843D01*
X2273893Y1390552D01*
G01X2290956Y1391135D02*
X2291393Y1394926D01*
X2292048Y1398135D01*
X2292921Y1401052D01*
X2294013Y1404260D01*
X2295760Y1408635D01*
X2287026D01*
G01X2304090Y1393759D02*
X2305399Y1392301D01*
X2306928Y1391427D01*
X2308893Y1391135D01*
X2310858Y1391718D01*
X2312386Y1392885D01*
X2313478Y1394926D01*
X2313696Y1397260D01*
X2313260Y1399593D01*
X2312168Y1401052D01*
X2310639Y1402218D01*
X2309111Y1402510D01*
X2307583Y1402218D01*
X2305618Y1401052D01*
X2306273Y1408635D01*
X2312168D01*
G01X2322463Y1390552D02*
X2330323Y1408635D01*
G01X2343893Y1391135D02*
X2345421Y1391427D01*
X2347168Y1392301D01*
X2348260Y1393759D01*
X2348696Y1395802D01*
X2348260Y1397843D01*
X2346950Y1399593D01*
X2344985Y1400468D01*
X2342801D01*
X2341491Y1401052D01*
X2340399Y1402510D01*
X2339963Y1404551D01*
X2340618Y1406593D01*
X2342146Y1408052D01*
X2343893Y1408635D01*
X2345639Y1408052D01*
X2347168Y1406593D01*
X2347823Y1404551D01*
X2347386Y1402510D01*
X2346295Y1401052D01*
X2344985Y1400468D01*
X2342801D01*
X2340836Y1399593D01*
X2339526Y1397843D01*
X2339090Y1395802D01*
X2339526Y1393759D01*
X2340618Y1392301D01*
X2342365Y1391427D01*
X2343893Y1391135D01*
G01X2361393Y1390552D02*
X2360956Y1390843D01*
Y1391427D01*
X2361393Y1391718D01*
X2361830Y1391427D01*
Y1390843D01*
X2361393Y1390552D01*
G01X2374090Y1393759D02*
X2375399Y1392301D01*
X2376928Y1391427D01*
X2378893Y1391135D01*
X2380858Y1391718D01*
X2382386Y1392885D01*
X2383478Y1394926D01*
X2383696Y1397260D01*
X2383260Y1399593D01*
X2382168Y1401052D01*
X2380639Y1402218D01*
X2379111Y1402510D01*
X2377583Y1402218D01*
X2375618Y1401052D01*
X2376273Y1408635D01*
X2382168D01*
G01X2223593Y1477935D02*
X2226649Y1460435D01*
X2230143Y1477935D01*
X2233636Y1460435D01*
X2236693Y1477935D01*
G01X2245023D02*
X2250263D01*
G01X2247643D02*
Y1460435D01*
G01X2245023D02*
X2250263D01*
G01X2260340D02*
Y1477935D01*
X2264706D01*
X2266453Y1477060D01*
X2267763Y1475893D01*
X2268855Y1474144D01*
X2269728Y1472101D01*
X2269946Y1469185D01*
X2269728Y1466268D01*
X2268855Y1464226D01*
X2267763Y1462476D01*
X2266453Y1461310D01*
X2264706Y1460435D01*
X2260340D01*
G01X2282643Y1477935D02*
Y1460435D01*
G01X2277621Y1477935D02*
X2287665D01*
G01X2295558Y1460435D02*
Y1477935D01*
G01X2304728D02*
Y1460435D01*
G01Y1469185D02*
X2295558D01*
G01X2316551Y1454602D02*
X2314368Y1457518D01*
X2313276Y1460435D01*
Y1472101D01*
X2314368Y1475018D01*
X2316551Y1477935D01*
G01X2328593Y1460435D02*
Y1472101D01*
G01Y1468893D02*
X2329248Y1470352D01*
X2330340Y1471518D01*
X2331868Y1472101D01*
X2333396Y1471518D01*
X2334488Y1470352D01*
X2335143Y1468893D01*
Y1460435D01*
G01Y1468893D02*
X2335798Y1470352D01*
X2336889Y1471518D01*
X2338418Y1472101D01*
X2339946Y1471518D01*
X2341038Y1470352D01*
X2341693Y1468602D01*
Y1460435D01*
G01X2352643Y1472101D02*
Y1460435D01*
G01Y1476768D02*
X2352206Y1477060D01*
Y1477643D01*
X2352643Y1477935D01*
X2353080Y1477643D01*
Y1477060D01*
X2352643Y1476768D01*
G01X2370143Y1460435D02*
Y1477935D01*
G01X2384368Y1462476D02*
X2385460Y1461310D01*
X2386988Y1460435D01*
X2388298D01*
X2389608Y1461018D01*
X2390481Y1461893D01*
X2390918Y1463059D01*
X2390700Y1464810D01*
X2389826Y1465685D01*
X2385896Y1467435D01*
X2385023Y1469477D01*
X2385460Y1470935D01*
X2386333Y1471810D01*
X2387643Y1472101D01*
X2388953Y1471810D01*
X2390263Y1470935D01*
G01X2406235Y1454602D02*
X2408418Y1457518D01*
X2409510Y1460435D01*
Y1472101D01*
X2408418Y1475018D01*
X2406235Y1477935D01*
G01X2514090Y1425785D02*
Y1443285D01*
X2518456D01*
X2520203Y1442410D01*
X2521513Y1441243D01*
X2522605Y1439494D01*
X2523478Y1437451D01*
X2523696Y1434535D01*
X2523478Y1431618D01*
X2522605Y1429576D01*
X2521513Y1427826D01*
X2520203Y1426660D01*
X2518456Y1425785D01*
X2514090D01*
G01X2532026D02*
Y1443285D01*
X2537266D01*
X2539013Y1442410D01*
X2540323Y1440368D01*
X2540760Y1438035D01*
X2540323Y1435702D01*
X2539231Y1433952D01*
X2537266Y1433076D01*
X2532026D01*
G01X2514090Y1391135D02*
Y1408635D01*
X2518456D01*
X2520203Y1407760D01*
X2521513Y1406593D01*
X2522605Y1404844D01*
X2523478Y1402801D01*
X2523696Y1399885D01*
X2523478Y1396968D01*
X2522605Y1394926D01*
X2521513Y1393176D01*
X2520203Y1392010D01*
X2518456Y1391135D01*
X2514090D01*
G01X2532026D02*
Y1408635D01*
X2537266D01*
X2539013Y1407760D01*
X2540323Y1405718D01*
X2540760Y1403385D01*
X2540323Y1401052D01*
X2539231Y1399302D01*
X2537266Y1398426D01*
X2532026D01*
G01X2501393Y1477935D02*
Y1460435D01*
G01X2496371Y1477935D02*
X2506415D01*
G01X2518893Y1460435D02*
Y1468310D01*
X2514526Y1477935D01*
G01X2523260D02*
X2518893Y1468310D01*
G01X2532026Y1460435D02*
Y1477935D01*
X2537266D01*
X2539013Y1477060D01*
X2540323Y1475018D01*
X2540760Y1472685D01*
X2540323Y1470352D01*
X2539231Y1468602D01*
X2537266Y1467726D01*
X2532026D01*
G01X2558260Y1460435D02*
X2549526D01*
Y1477935D01*
X2558260D01*
G01X2554766Y1469477D02*
X2549526D01*
G01X2645776Y1443285D02*
Y1425785D01*
X2654510D01*
G01X2662840Y1428409D02*
X2664149Y1426951D01*
X2665678Y1426077D01*
X2667643Y1425785D01*
X2669608Y1426368D01*
X2671136Y1427535D01*
X2672228Y1429576D01*
X2672446Y1431910D01*
X2672010Y1434243D01*
X2670918Y1435702D01*
X2669389Y1436868D01*
X2667861Y1437160D01*
X2666333Y1436868D01*
X2664368Y1435702D01*
X2665023Y1443285D01*
X2670918D01*
G01X2681213Y1425202D02*
X2689073Y1443285D01*
G01X2698276D02*
Y1425785D01*
X2707010D01*
G01X2719706D02*
X2720143Y1429576D01*
X2720798Y1432785D01*
X2721671Y1435702D01*
X2722763Y1438910D01*
X2724510Y1443285D01*
X2715776D01*
G01X2645776Y1408635D02*
Y1391135D01*
X2654510D01*
G01X2662840Y1393759D02*
X2664149Y1392301D01*
X2665678Y1391427D01*
X2667643Y1391135D01*
X2669608Y1391718D01*
X2671136Y1392885D01*
X2672228Y1394926D01*
X2672446Y1397260D01*
X2672010Y1399593D01*
X2670918Y1401052D01*
X2669389Y1402218D01*
X2667861Y1402510D01*
X2666333Y1402218D01*
X2664368Y1401052D01*
X2665023Y1408635D01*
X2670918D01*
G01X2681213Y1390552D02*
X2689073Y1408635D01*
G01X2698276D02*
Y1391135D01*
X2707010D01*
G01X2719706D02*
X2720143Y1394926D01*
X2720798Y1398135D01*
X2721671Y1401052D01*
X2722763Y1404260D01*
X2724510Y1408635D01*
X2715776D01*
G01X2602026Y1460435D02*
Y1477935D01*
X2607485D01*
X2609231Y1477060D01*
X2610323Y1475893D01*
X2610760Y1473560D01*
X2610323Y1471226D01*
X2609013Y1469768D01*
X2607485Y1468893D01*
X2602026D01*
G01X2607485D02*
X2610760Y1460435D01*
G01X2620618Y1468310D02*
X2627605D01*
X2626950Y1470352D01*
X2625858Y1471518D01*
X2624330Y1472101D01*
X2622801Y1471810D01*
X2621491Y1470935D01*
X2620618Y1468893D01*
X2620181Y1467143D01*
Y1465393D01*
X2620618Y1463643D01*
X2621710Y1461893D01*
X2623020Y1460727D01*
X2624548Y1460435D01*
X2626076Y1461018D01*
X2627605Y1462768D01*
G01X2640083Y1460435D02*
Y1475310D01*
X2640520Y1476768D01*
X2641393Y1477643D01*
X2642703Y1477935D01*
X2644013Y1477352D01*
X2644668Y1475893D01*
G01X2642048Y1470935D02*
X2637681D01*
G01X2658893Y1459852D02*
X2658456Y1460143D01*
Y1460727D01*
X2658893Y1461018D01*
X2659330Y1460727D01*
Y1460143D01*
X2658893Y1459852D01*
G01X2689526Y1460435D02*
Y1477935D01*
X2694766D01*
X2696513Y1477060D01*
X2697823Y1475018D01*
X2698260Y1472685D01*
X2697823Y1470352D01*
X2696731Y1468602D01*
X2694766Y1467726D01*
X2689526D01*
G01X2711393Y1460435D02*
Y1477935D01*
G01X2732823Y1460435D02*
Y1472101D01*
G01Y1470060D02*
X2731950Y1471226D01*
X2730639Y1471810D01*
X2729111Y1472101D01*
X2727583Y1471518D01*
X2726273Y1470352D01*
X2725399Y1468602D01*
X2724963Y1466268D01*
X2725399Y1463935D01*
X2726273Y1462185D01*
X2727583Y1461018D01*
X2729111Y1460435D01*
X2730639Y1460727D01*
X2731950Y1461601D01*
X2732823Y1462768D01*
G01X2742681Y1460435D02*
Y1472101D01*
G01Y1469185D02*
X2743555Y1470643D01*
X2744865Y1471810D01*
X2746611Y1472101D01*
X2748139Y1471810D01*
X2749450Y1470643D01*
X2750105Y1468602D01*
Y1460435D01*
G01X2760618Y1468310D02*
X2767605D01*
X2766950Y1470352D01*
X2765858Y1471518D01*
X2764330Y1472101D01*
X2762801Y1471810D01*
X2761491Y1470935D01*
X2760618Y1468893D01*
X2760181Y1467143D01*
Y1465393D01*
X2760618Y1463643D01*
X2761710Y1461893D01*
X2763020Y1460727D01*
X2764548Y1460435D01*
X2766076Y1461018D01*
X2767605Y1462768D01*
G01X2881693Y1437451D02*
Y1425785D01*
G01Y1442118D02*
X2881256Y1442410D01*
Y1442993D01*
X2881693Y1443285D01*
X2882130Y1442993D01*
Y1442410D01*
X2881693Y1442118D01*
G01X2895918Y1427826D02*
X2897010Y1426660D01*
X2898538Y1425785D01*
X2899848D01*
X2901158Y1426368D01*
X2902031Y1427243D01*
X2902468Y1428409D01*
X2902250Y1430160D01*
X2901376Y1431035D01*
X2897446Y1432785D01*
X2896573Y1434827D01*
X2897010Y1436285D01*
X2897883Y1437160D01*
X2899193Y1437451D01*
X2900503Y1437160D01*
X2901813Y1436285D01*
G01X2929171Y1425785D02*
Y1443285D01*
X2939215Y1425785D01*
Y1443285D01*
G01X2951693Y1425785D02*
X2949946Y1426077D01*
X2948418Y1427243D01*
X2947108Y1428993D01*
X2946234Y1431035D01*
X2945798Y1433368D01*
Y1435702D01*
X2946234Y1438035D01*
X2947108Y1440077D01*
X2948418Y1441826D01*
X2949946Y1442993D01*
X2951693Y1443285D01*
X2953439Y1442993D01*
X2954968Y1441826D01*
X2956278Y1440077D01*
X2957152Y1438035D01*
X2957588Y1435702D01*
Y1433368D01*
X2957152Y1431035D01*
X2956278Y1428993D01*
X2954968Y1427243D01*
X2953439Y1426077D01*
X2951693Y1425785D01*
G01X2969193Y1443285D02*
Y1425785D01*
G01X2964171Y1443285D02*
X2974215D01*
G01X3000481Y1437451D02*
Y1429285D01*
X3001355Y1427243D01*
X3002665Y1426077D01*
X3004193Y1425785D01*
X3005721Y1426077D01*
X3007031Y1427243D01*
X3007905Y1429285D01*
G01Y1425785D02*
Y1437451D01*
G01X3018418Y1427826D02*
X3019510Y1426660D01*
X3021038Y1425785D01*
X3022348D01*
X3023658Y1426368D01*
X3024531Y1427243D01*
X3024968Y1428409D01*
X3024750Y1430160D01*
X3023876Y1431035D01*
X3019946Y1432785D01*
X3019073Y1434827D01*
X3019510Y1436285D01*
X3020383Y1437160D01*
X3021693Y1437451D01*
X3023003Y1437160D01*
X3024313Y1436285D01*
G01X3035918Y1433660D02*
X3042905D01*
X3042250Y1435702D01*
X3041158Y1436868D01*
X3039630Y1437451D01*
X3038101Y1437160D01*
X3036791Y1436285D01*
X3035918Y1434243D01*
X3035481Y1432493D01*
Y1430743D01*
X3035918Y1428993D01*
X3037010Y1427243D01*
X3038320Y1426077D01*
X3039848Y1425785D01*
X3041376Y1426368D01*
X3042905Y1428118D01*
G01X3060623Y1443285D02*
Y1425785D01*
G01Y1428409D02*
X3059750Y1426951D01*
X3058439Y1426077D01*
X3056911Y1425785D01*
X3055165Y1426368D01*
X3053855Y1427826D01*
X3052981Y1429576D01*
X3052763Y1431618D01*
X3052981Y1433660D01*
X3053855Y1435410D01*
X3055165Y1436868D01*
X3056911Y1437451D01*
X3058439Y1437160D01*
X3059531Y1436576D01*
X3060623Y1435410D01*
G01X2806890Y1459852D02*
X2816496Y1472685D01*
G01X2811693Y1475018D02*
Y1457518D01*
G01X2816496Y1459852D02*
X2806890Y1472685D01*
G01X2805143Y1466268D02*
X2818243D01*
G01X2843855D02*
X2849531D01*
G01X2876890Y1460435D02*
Y1477935D01*
X2881256D01*
X2883003Y1477060D01*
X2884313Y1475893D01*
X2885405Y1474144D01*
X2886278Y1472101D01*
X2886496Y1469185D01*
X2886278Y1466268D01*
X2885405Y1464226D01*
X2884313Y1462476D01*
X2883003Y1461310D01*
X2881256Y1460435D01*
X2876890D01*
G01X2895918Y1468310D02*
X2902905D01*
X2902250Y1470352D01*
X2901158Y1471518D01*
X2899630Y1472101D01*
X2898101Y1471810D01*
X2896791Y1470935D01*
X2895918Y1468893D01*
X2895481Y1467143D01*
Y1465393D01*
X2895918Y1463643D01*
X2897010Y1461893D01*
X2898320Y1460727D01*
X2899848Y1460435D01*
X2901376Y1461018D01*
X2902905Y1462768D01*
G01X2912981Y1460435D02*
Y1472101D01*
G01Y1469185D02*
X2913855Y1470643D01*
X2915165Y1471810D01*
X2916911Y1472101D01*
X2918439Y1471810D01*
X2919750Y1470643D01*
X2920405Y1468602D01*
Y1460435D01*
G01X2934193D02*
X2932883Y1460727D01*
X2931573Y1461893D01*
X2930699Y1463935D01*
X2930263Y1466268D01*
X2930699Y1468602D01*
X2931573Y1470643D01*
X2932883Y1471810D01*
X2934193Y1472101D01*
X2935503Y1471810D01*
X2936813Y1470643D01*
X2937686Y1468602D01*
X2937905Y1466268D01*
X2937686Y1463935D01*
X2936813Y1461893D01*
X2935503Y1460727D01*
X2934193Y1460435D01*
G01X2951693Y1477935D02*
Y1460435D01*
G01X2948636Y1472101D02*
X2954750D01*
G01X2965918Y1468310D02*
X2972905D01*
X2972250Y1470352D01*
X2971158Y1471518D01*
X2969630Y1472101D01*
X2968101Y1471810D01*
X2966791Y1470935D01*
X2965918Y1468893D01*
X2965481Y1467143D01*
Y1465393D01*
X2965918Y1463643D01*
X2967010Y1461893D01*
X2968320Y1460727D01*
X2969848Y1460435D01*
X2971376Y1461018D01*
X2972905Y1462768D01*
G01X2983418Y1462476D02*
X2984510Y1461310D01*
X2986038Y1460435D01*
X2987348D01*
X2988658Y1461018D01*
X2989531Y1461893D01*
X2989968Y1463059D01*
X2989750Y1464810D01*
X2988876Y1465685D01*
X2984946Y1467435D01*
X2984073Y1469477D01*
X2984510Y1470935D01*
X2985383Y1471810D01*
X2986693Y1472101D01*
X2988003Y1471810D01*
X2989313Y1470935D01*
G01X3021693Y1477935D02*
Y1460435D01*
G01X3018636Y1472101D02*
X3024750D01*
G01X3035481Y1460435D02*
Y1477935D01*
G01Y1469477D02*
X3036573Y1470935D01*
X3037665Y1471810D01*
X3039411Y1472101D01*
X3040721Y1471810D01*
X3042250Y1470643D01*
X3042905Y1468893D01*
Y1460435D01*
G01X3060623D02*
Y1472101D01*
G01Y1470060D02*
X3059750Y1471226D01*
X3058439Y1471810D01*
X3056911Y1472101D01*
X3055383Y1471518D01*
X3054073Y1470352D01*
X3053199Y1468602D01*
X3052763Y1466268D01*
X3053199Y1463935D01*
X3054073Y1462185D01*
X3055383Y1461018D01*
X3056911Y1460435D01*
X3058439Y1460727D01*
X3059750Y1461601D01*
X3060623Y1462768D01*
G01X3074193Y1477935D02*
Y1460435D01*
G01X3071136Y1472101D02*
X3077250D01*
G01X3109193Y1477935D02*
Y1460435D01*
G01X3106136Y1472101D02*
X3112250D01*
G01X3122981Y1460435D02*
Y1477935D01*
G01Y1469477D02*
X3124073Y1470935D01*
X3125165Y1471810D01*
X3126911Y1472101D01*
X3128221Y1471810D01*
X3129750Y1470643D01*
X3130405Y1468893D01*
Y1460435D01*
G01X3144193Y1472101D02*
Y1460435D01*
G01Y1476768D02*
X3143756Y1477060D01*
Y1477643D01*
X3144193Y1477935D01*
X3144630Y1477643D01*
Y1477060D01*
X3144193Y1476768D01*
G01X3158418Y1462476D02*
X3159510Y1461310D01*
X3161038Y1460435D01*
X3162348D01*
X3163658Y1461018D01*
X3164531Y1461893D01*
X3164968Y1463059D01*
X3164750Y1464810D01*
X3163876Y1465685D01*
X3159946Y1467435D01*
X3159073Y1469477D01*
X3159510Y1470935D01*
X3160383Y1471810D01*
X3161693Y1472101D01*
X3163003Y1471810D01*
X3164313Y1470935D01*
G01X3194073Y1477935D02*
X3199313D01*
G01X3196693D02*
Y1460435D01*
G01X3194073D02*
X3199313D01*
G01X3207643D02*
Y1472101D01*
G01Y1468893D02*
X3208298Y1470352D01*
X3209390Y1471518D01*
X3210918Y1472101D01*
X3212446Y1471518D01*
X3213538Y1470352D01*
X3214193Y1468893D01*
Y1460435D01*
G01Y1468893D02*
X3214848Y1470352D01*
X3215939Y1471518D01*
X3217468Y1472101D01*
X3218996Y1471518D01*
X3220088Y1470352D01*
X3220743Y1468602D01*
Y1460435D01*
G01X3227763Y1454602D02*
Y1472101D01*
G01Y1469477D02*
X3228855Y1470935D01*
X3229946Y1471810D01*
X3231693Y1472101D01*
X3233221Y1471810D01*
X3234750Y1470352D01*
X3235405Y1468310D01*
X3235623Y1466268D01*
X3235405Y1464226D01*
X3234750Y1462185D01*
X3233439Y1461018D01*
X3231693Y1460435D01*
X3230165Y1460727D01*
X3228636Y1461601D01*
X3227763Y1462768D01*
G01X3245918Y1468310D02*
X3252905D01*
X3252250Y1470352D01*
X3251158Y1471518D01*
X3249630Y1472101D01*
X3248101Y1471810D01*
X3246791Y1470935D01*
X3245918Y1468893D01*
X3245481Y1467143D01*
Y1465393D01*
X3245918Y1463643D01*
X3247010Y1461893D01*
X3248320Y1460727D01*
X3249848Y1460435D01*
X3251376Y1461018D01*
X3252905Y1462768D01*
G01X3270623Y1477935D02*
Y1460435D01*
G01Y1463059D02*
X3269750Y1461601D01*
X3268439Y1460727D01*
X3266911Y1460435D01*
X3265165Y1461018D01*
X3263855Y1462476D01*
X3262981Y1464226D01*
X3262763Y1466268D01*
X3262981Y1468310D01*
X3263855Y1470060D01*
X3265165Y1471518D01*
X3266911Y1472101D01*
X3268439Y1471810D01*
X3269531Y1471226D01*
X3270623Y1470060D01*
G01X3288123Y1460435D02*
Y1472101D01*
G01Y1470060D02*
X3287250Y1471226D01*
X3285939Y1471810D01*
X3284411Y1472101D01*
X3282883Y1471518D01*
X3281573Y1470352D01*
X3280699Y1468602D01*
X3280263Y1466268D01*
X3280699Y1463935D01*
X3281573Y1462185D01*
X3282883Y1461018D01*
X3284411Y1460435D01*
X3285939Y1460727D01*
X3287250Y1461601D01*
X3288123Y1462768D01*
G01X3297981Y1460435D02*
Y1472101D01*
G01Y1469185D02*
X3298855Y1470643D01*
X3300165Y1471810D01*
X3301911Y1472101D01*
X3303439Y1471810D01*
X3304750Y1470643D01*
X3305405Y1468602D01*
Y1460435D01*
G01X3322686Y1470643D02*
X3321158Y1471810D01*
X3319848Y1472101D01*
X3318101Y1471518D01*
X3316791Y1470352D01*
X3315918Y1468310D01*
X3315699Y1466268D01*
X3315918Y1464226D01*
X3316791Y1462476D01*
X3318101Y1461018D01*
X3319848Y1460435D01*
X3321376Y1461018D01*
X3322686Y1462185D01*
G01X3333418Y1468310D02*
X3340405D01*
X3339750Y1470352D01*
X3338658Y1471518D01*
X3337130Y1472101D01*
X3335601Y1471810D01*
X3334291Y1470935D01*
X3333418Y1468893D01*
X3332981Y1467143D01*
Y1465393D01*
X3333418Y1463643D01*
X3334510Y1461893D01*
X3335820Y1460727D01*
X3337348Y1460435D01*
X3338876Y1461018D01*
X3340405Y1462768D01*
G01X0Y3937D02*
G03X3937Y0I3937J0D01*
G01X0Y3937D02*
G03X3937Y0I3937J0D01*
G01D02*
X779528D01*
G01X3937D02*
X779528D01*
G01X0Y1456693D02*
Y3937D01*
G01Y1456693D02*
Y3937D01*
G01X7874Y1460630D02*
X3937D01*
G01D02*
X7874D01*
G01X3937D02*
G03X0Y1456693I0J-3937D01*
G01X3937Y1460630D02*
G03X0Y1456693I0J-3937D01*
G01X101378Y1519685D02*
G03X97441Y1515748I0J-3937D01*
G01X101378Y1519685D02*
G03X97441Y1515748I0J-3937D01*
G01D02*
Y1509055D01*
G01Y1515748D02*
Y1509055D01*
G01X93504Y1505118D02*
X67913D01*
G01X93504D02*
G03X97441Y1509055I0J3937D01*
G01X93504Y1505118D02*
G03X97441Y1509055I0J3937D01*
G01X67913Y1505118D02*
X93504D01*
G01X63976Y1515748D02*
G03X60039Y1519685I-3937J0D01*
G01X63976Y1515748D02*
G03X60039Y1519685I-3937J0D01*
G01X63976Y1509055D02*
Y1515748D01*
G01Y1509055D02*
G03X67913Y1505118I3937J0D01*
G01X63976Y1509055D02*
G03X67913Y1505118I3937J0D01*
G01X63976Y1515748D02*
Y1509055D01*
G01X7874Y1460630D02*
G03X11811Y1464567I0J3937D01*
G01X7874Y1460630D02*
G03X11811Y1464567I0J3937D01*
G01X15748Y1519685D02*
G03X11811Y1515748I0J-3937D01*
G01X15748Y1519685D02*
G03X11811Y1515748I0J-3937D01*
G01D02*
Y1464567D01*
G01Y1515748D02*
Y1464567D01*
G01X60039Y1519685D02*
X15748D01*
G01X60039D02*
X15748D01*
G01X141181Y277843D02*
G03X148106Y264712I37662J11471D01*
G01X141181Y277843D02*
G03X148106Y264712I37662J11471D01*
G01X141181Y277843D02*
G03X121220I-9980J-3040D01*
G01X114295Y264712D02*
G03X121220Y277843I-30737J24602D01*
G01X141181D02*
G03X121220I-9980J-3040D01*
G01X114295Y264712D02*
G03X121220Y277843I-30737J24601D01*
G01X114295Y264712D02*
G03X148106I16905J-13531D01*
G01X114295D02*
G03X148106I16905J-13531D01*
G01X141181Y730599D02*
G03X148106Y717468I37662J11471D01*
G01X141181Y730599D02*
G03X148106Y717468I37662J11471D01*
G01X141181Y730599D02*
G03X121220I-9980J-3040D01*
G01X114295Y717468D02*
G03X121220Y730599I-30737J24601D01*
G01X141181D02*
G03X121220I-9980J-3040D01*
G01X114295Y717468D02*
G03X121220Y730599I-30737J24601D01*
G01X114295Y717468D02*
G03X148106I16905J-13531D01*
G01X114295D02*
G03X148106I16905J-13531D01*
G01X114295Y1170224D02*
G03X148106I16905J-13531D01*
G01X114295D02*
G03X148106I16905J-13531D01*
G01X141181Y1183355D02*
G03X148106Y1170224I37662J11471D01*
G01X141181Y1183355D02*
G03X148106Y1170224I37662J11471D01*
G01X141181Y1183355D02*
G03X121220I-9980J-3040D01*
G01X141181D02*
G03X121220I-9980J-3040D01*
G01X114295Y1170224D02*
G03X121220Y1183355I-30737J24602D01*
G01X114295Y1170224D02*
G03X121220Y1183355I-30737J24601D01*
G01X280709Y1519685D02*
X101378D01*
G01X280709D02*
X101378D01*
G01X284646Y1515748D02*
G03X280709Y1519685I-3937J0D01*
G01X284646Y1515748D02*
G03X280709Y1519685I-3937J0D01*
G01X284646Y1500000D02*
Y1515748D01*
G01Y1500000D02*
G03X288583Y1496063I3937J0D01*
G01X493307D02*
X288583D01*
G01X284646Y1500000D02*
G03X288583Y1496063I3937J0D01*
G01X493307D02*
X288583D01*
G01X284646Y1515748D02*
Y1500000D01*
G01X389213Y277843D02*
G03X369252I-9981J-3040D01*
G01X389213D02*
G03X369252I-9981J-3040D01*
G01X362327Y264712D02*
G03X369252Y277843I-30737J24602D01*
G01X362327Y264712D02*
G03X369252Y277843I-30737J24602D01*
G01X362327Y264712D02*
G03X396138I16905J-13531D01*
G01X362327D02*
G03X396138I16905J-13531D01*
G01X389213Y730599D02*
G03X369252I-9981J-3040D01*
G01X389213D02*
G03X369252I-9981J-3040D01*
G01X362327Y717468D02*
G03X369252Y730599I-30737J24602D01*
G01X362327Y717468D02*
G03X369252Y730599I-30737J24602D01*
G01X362327Y717468D02*
G03X396138I16905J-13531D01*
G01X362327D02*
G03X396138I16905J-13531D01*
G01X362327Y1170224D02*
G03X396138I16905J-13531D01*
G01X362327D02*
G03X396138I16905J-13531D01*
G01X389213Y1183355D02*
G03X369252I-9981J-3040D01*
G01X389213D02*
G03X369252I-9981J-3040D01*
G01X362327Y1170224D02*
G03X369252Y1183355I-30737J24602D01*
G01X362327Y1170224D02*
G03X369252Y1183355I-30737J24602D01*
G01X322441Y1503937D02*
G03Y1496063I0J-3937D01*
G01X459449Y1503937D02*
X322441D01*
G01X459449D02*
X322441D01*
G01D02*
G03Y1496063I0J-3937D01*
G01X296457Y1519685D02*
G03X292520Y1515748I0J-3937D01*
G01X296457Y1519685D02*
X485433D01*
G01X296457D02*
G03X292520Y1515748I0J-3937D01*
G01X296457Y1519685D02*
X485433D01*
G01X304331Y1503937D02*
X292520D01*
G01Y1515748D02*
Y1503937D01*
G01X304331D02*
X292520D01*
G01Y1515748D02*
Y1503937D01*
G01X304331Y1496063D02*
G03Y1503937I0J3937D01*
G01Y1496063D02*
G03Y1503937I0J3937D01*
G01X389213Y277843D02*
G03X396138Y264712I37662J11471D01*
G01X389213Y277843D02*
G03X396138Y264712I37662J11470D01*
G01X389213Y730599D02*
G03X396138Y717468I37662J11471D01*
G01X389213Y730599D02*
G03X396138Y717468I37662J11470D01*
G01X389213Y1183355D02*
G03X396138Y1170224I37662J11471D01*
G01X389213Y1183355D02*
G03X396138Y1170224I37662J11470D01*
G01X477559Y1503937D02*
G03Y1496063I0J-3937D01*
G01X459449D02*
G03Y1503937I0J3937D01*
G01X489370D02*
X477559D01*
G01D02*
G03Y1496063I0J-3937D01*
G01X459449D02*
G03Y1503937I0J3937D01*
G01X489370D02*
X477559D01*
G01X489370Y1515748D02*
G03X485433Y1519685I-3937J0D01*
G01X489370Y1515748D02*
G03X485433Y1519685I-3937J0D01*
G01X501181D02*
G03X497244Y1515748I0J-3937D01*
G01X680512Y1519685D02*
X501181D01*
G01D02*
G03X497244Y1515748I0J-3937D01*
G01X680512Y1519685D02*
X501181D01*
G01X489370Y1515748D02*
Y1503937D01*
G01X493307Y1496063D02*
G03X497244Y1500000I0J3937D01*
G01Y1515748D02*
Y1500000D01*
G01X489370Y1515748D02*
Y1503937D01*
G01X493307Y1496063D02*
G03X497244Y1500000I0J3937D01*
G01Y1515748D02*
Y1500000D01*
G01X637244Y277843D02*
G03X644169Y264712I37662J11471D01*
G01X637244Y277843D02*
G03X644169Y264712I37662J11471D01*
G01X637244Y277843D02*
G03X617283I-9980J-3040D01*
G01X610358Y264712D02*
G03X617283Y277843I-30737J24602D01*
G01X637244D02*
G03X617283I-9980J-3040D01*
G01X610358Y264712D02*
G03X617283Y277843I-30737J24601D01*
G01X610358Y264712D02*
G03X644169I16906J-13531D01*
G01X610358D02*
G03X644169I16906J-13531D01*
G01X637244Y730599D02*
G03X644169Y717468I37662J11471D01*
G01X637244Y730599D02*
G03X644169Y717468I37662J11471D01*
G01X637244Y730599D02*
G03X617283I-9980J-3040D01*
G01X610358Y717468D02*
G03X617283Y730599I-30737J24601D01*
G01X637244D02*
G03X617283I-9980J-3040D01*
G01X610358Y717468D02*
G03X617283Y730599I-30737J24601D01*
G01X610358Y717468D02*
G03X644169I16906J-13531D01*
G01X610358D02*
G03X644169I16906J-13531D01*
G01X610358Y1170224D02*
G03X644169I16906J-13531D01*
G01X610358D02*
G03X644169I16906J-13531D01*
G01X637244Y1183355D02*
G03X644169Y1170224I37662J11471D01*
G01X637244Y1183355D02*
G03X644169Y1170224I37662J11471D01*
G01X637244Y1183355D02*
G03X617283I-9980J-3040D01*
G01X637244D02*
G03X617283I-9980J-3040D01*
G01X610358Y1170224D02*
G03X617283Y1183355I-30737J24602D01*
G01X610358Y1170224D02*
G03X617283Y1183355I-30737J24601D01*
G01X730339Y383610D02*
G03X764149I16905J-13531D01*
G01X730339Y383609D02*
G03X764150I16905J-13530D01*
G01X757225Y396741D02*
G03X764149Y383610I37663J11469D01*
G01X757224Y396741D02*
G03X764150Y383609I37662J11471D01*
G01X757225Y396741D02*
G03X737264I-9981J-3040D01*
G01X730339Y383610D02*
G03X737264Y396741I-30737J24602D01*
G01X757224D02*
G03X737264I-9980J-3041D01*
G01X730339Y383609D02*
G03X737264Y396741I-30738J24601D01*
G01X757225Y829811D02*
G03X764149Y816680I37663J11469D01*
G01X757224Y829811D02*
G03X764150Y816680I37662J11473D01*
G01X757225Y829811D02*
G03X737264I-9981J-3039D01*
G01X757224D02*
G03X737264I-9980J-3040D01*
G01X730339Y816680D02*
G03X737264Y829811I-30737J24602D01*
G01X730339Y816680D02*
G03X737264Y829811I-30737J24602D01*
G01X730339Y816680D02*
G03X764149I16905J-13531D01*
G01X730339D02*
G03X764150I16905J-13531D01*
G01X721850Y1519685D02*
G03X717913Y1515748I0J-3937D01*
G01X775591Y1519685D02*
X721850D01*
G01D02*
G03X717913Y1515748I0J-3937D01*
G01X775591Y1519685D02*
X721850D01*
G01X713976Y1505118D02*
G03X717913Y1509055I0J3937D01*
G01Y1515748D02*
Y1509055D01*
G01X713976Y1505118D02*
G03X717913Y1509055I0J3937D01*
G01Y1515748D02*
Y1509055D01*
G01X684449Y1515748D02*
G03X680512Y1519685I-3937J0D01*
G01X684449Y1515748D02*
G03X680512Y1519685I-3937J0D01*
G01X684449Y1509055D02*
Y1515748D01*
G01Y1509055D02*
G03X688386Y1505118I3937J0D01*
G01X713976D02*
X688386D01*
G01X684449Y1509055D02*
G03X688386Y1505118I3937J0D01*
G01D02*
X713976D01*
G01X684449Y1515748D02*
Y1509055D01*
G01X791339Y3937D02*
G03X795276Y0I3937J0D01*
G01D02*
X892317D01*
G01X791339Y3937D02*
Y23622D01*
G01Y3937D02*
G03X795276Y0I3937J0D01*
G01X791339Y3937D02*
Y23622D01*
G01X795276Y0D02*
X892317D01*
G01X783465Y54331D02*
G03X791339I3937J0D01*
G01X783465D02*
G03X791339I3937J0D01*
G01Y23622D02*
G03X783465I-3937J0D01*
G01X791339D02*
G03X783465I-3937J0D01*
G01X779528Y0D02*
G03X783465Y3937I0J3937D01*
G01X779528Y0D02*
G03X783465Y3937I0J3937D01*
G01X791339Y54331D02*
Y181890D01*
G01Y54331D02*
Y181890D01*
G01X783465Y3937D02*
Y185827D01*
G01Y3937D02*
Y185827D01*
G01X811024Y181890D02*
G03X822835Y193701I0J11811D01*
G01X791339Y181890D02*
X811024D01*
G01D02*
G03X822835Y193701I0J11811D01*
G01X791339Y181890D02*
X811024D01*
G01X787402Y189764D02*
G03X783465Y185827I0J-3937D01*
G01X787402Y189764D02*
G03X783465Y185827I0J-3937D01*
G01X811024Y189764D02*
G03X814961Y193701I0J3937D01*
G01X787402Y189764D02*
X811024D01*
G01D02*
G03X814961Y193701I0J3937D01*
G01X787402Y189764D02*
X811024D01*
G01X822835Y193701D02*
Y240157D01*
G01Y193701D02*
Y240157D01*
G01X814961Y193701D02*
Y244094D01*
G01Y193701D02*
Y244094D01*
G01X818898Y248031D02*
G03X814961Y244094I0J-3937D01*
G01X818898Y248031D02*
G03X814961Y244094I0J-3937D01*
G01X928098Y240157D02*
X822835D01*
G01X928098D02*
X822835D01*
G01X818898Y248031D02*
X1055118D01*
G01D02*
X818898D01*
G01X954331Y1503937D02*
X817323D01*
G01X954331D02*
X817323D01*
G01X791339Y1519685D02*
G03X787402Y1515748I0J-3937D01*
G01X791339Y1519685D02*
X980315D01*
G01X791339D02*
G03X787402Y1515748I0J-3937D01*
G01X791339Y1519685D02*
X980315D01*
G01X817323Y1503937D02*
G03Y1496063I0J-3937D01*
G01X799213D02*
G03Y1503937I0J3937D01*
G01D02*
X787402D01*
G01Y1515748D02*
Y1503937D01*
G01X799213D02*
X787402D01*
G01X817323D02*
G03Y1496063I0J-3937D01*
G01X799213D02*
G03Y1503937I0J3937D01*
G01X787402Y1515748D02*
Y1503937D01*
G01X779528Y1515748D02*
G03X775591Y1519685I-3937J0D01*
G01X779528Y1515748D02*
G03X775591Y1519685I-3937J0D01*
G01X779528Y1500000D02*
Y1515748D01*
G01Y1500000D02*
G03X783465Y1496063I3937J0D01*
G01X988189D02*
X783465D01*
G01X779528Y1500000D02*
G03X783465Y1496063I3937J0D01*
G01X988189D02*
X783465D01*
G01X779528Y1515748D02*
Y1500000D01*
G01X900191Y0D02*
G03X892317I-3937J0D01*
G01X896254D02*
Y-394D01*
G01Y0D02*
Y394D01*
G01X895762Y0D02*
X896746D01*
G01X900191D02*
G03X892317I-3937J0D01*
G01X900191D02*
X1212598D01*
G01X900191D02*
X1212598D01*
G01X953294Y248031D02*
G03Y240157I1J-3937D01*
G01X1051181D02*
X953294D01*
G01Y248031D02*
G03Y240157I1J-3937D01*
G01X928098D02*
G03Y248031I0J3937D01*
G01Y240157D02*
G03Y248031I0J3937D01*
G01X1051181Y240157D02*
X953294D01*
G01X971398Y718788D02*
G03X951437I-9980J-3040D01*
G01X944512Y705657D02*
G03X951437Y718788I-30737J24602D01*
G01X971398D02*
G03X951437I-9980J-3040D01*
G01X944512Y705657D02*
G03X951437Y718788I-30737J24602D01*
G01X944512Y705657D02*
G03X978323I16905J-13531D01*
G01X944512D02*
G03X978323I16905J-13531D01*
G01X944512Y974161D02*
G03X978323I16905J-13531D01*
G01X944512D02*
G03X978323I16905J-13531D01*
G01X971398Y987292D02*
G03X951437I-9980J-3040D01*
G01X944512Y974161D02*
G03X951437Y987292I-30737J24602D01*
G01X971398D02*
G03X951437I-9980J-3040D01*
G01X944512Y974161D02*
G03X951437Y987292I-30737J24602D01*
G01X954331Y1496063D02*
G03Y1503937I0J3937D01*
G01Y1496063D02*
G03Y1503937I0J3937D01*
G01X1051181Y193701D02*
G03X1062992Y181890I11811J0D01*
G01X1051181Y193701D02*
G03X1062992Y181890I11811J0D01*
G01X1051181Y240157D02*
Y193701D01*
G01Y240157D02*
Y193701D01*
G01X971398Y718788D02*
G03X978323Y705657I37662J11471D01*
G01X971398Y718788D02*
G03X978323Y705657I37662J11470D01*
G01X971398Y987292D02*
G03X978323Y974161I37662J11471D01*
G01X971398Y987292D02*
G03X978323Y974161I37662J11470D01*
G01X1059196Y1519685D02*
X996063D01*
G01X1059196D02*
X996063D01*
G01X984252Y1515748D02*
G03X980315Y1519685I-3937J0D01*
G01X984252Y1515748D02*
G03X980315Y1519685I-3937J0D01*
G01X996063D02*
G03X992126Y1515748I0J-3937D01*
G01X996063Y1519685D02*
G03X992126Y1515748I0J-3937D01*
G01X972441Y1503937D02*
G03Y1496063I0J-3937D01*
G01X984252Y1503937D02*
X972441D01*
G01X984252Y1515748D02*
Y1503937D01*
G01X972441D02*
G03Y1496063I0J-3937D01*
G01X988189D02*
G03X992126Y1500000I0J3937D01*
G01Y1515748D02*
Y1500000D01*
G01X984252Y1515748D02*
Y1503937D01*
G01D02*
X972441D01*
G01X988189Y1496063D02*
G03X992126Y1500000I0J3937D01*
G01Y1515748D02*
Y1500000D01*
G01X1133071Y189764D02*
G03Y181890I0J-3937D01*
G01D02*
X1216535D01*
G01X1133071D02*
X1216535D01*
G01X1133071Y189764D02*
G03Y181890I0J-3937D01*
G01X1102362D02*
G03Y189764I0J3937D01*
G01Y181890D02*
G03Y189764I0J3937D01*
G01X1062992Y181890D02*
X1102362D01*
G01X1062992D02*
X1102362D01*
G01X1059055Y244094D02*
G03X1055118Y248031I-3937J0D01*
G01X1059055Y244094D02*
G03X1055118Y248031I-3937J0D01*
G01X1059055Y244094D02*
Y193701D01*
G01Y244094D02*
Y193701D01*
G01X1062992Y189764D02*
X1220472D01*
G01X1059055Y193701D02*
G03X1062992Y189764I3937J0D01*
G01X1059055Y193701D02*
G03X1062992Y189764I3937J0D01*
G01D02*
X1220472D01*
G01X1085630Y1417323D02*
G03X1089567Y1421260I0J3937D01*
G01X1085630Y1417323D02*
G03X1089567Y1421260I0J3937D01*
G01X1072638D02*
G03X1076575Y1417322I3937J-1D01*
G01X1085630Y1417323D02*
X1076575D01*
G01X1072638Y1421260D02*
G03X1076575Y1417323I3937J0D01*
G01D02*
X1085630D01*
G01X1089567Y1506243D02*
Y1421260D01*
G01Y1506243D02*
Y1421260D01*
G01X1072638D02*
Y1506243D01*
G01D02*
Y1421260D01*
G01X1103009Y1519685D02*
G03X1100225Y1518532I0J-3937D01*
G01X1207283Y1519685D02*
X1103009D01*
G01D02*
G03X1100225Y1518532I0J-3937D01*
G01X1207283Y1519685D02*
X1103009D01*
G01X1090720Y1509027D02*
G03X1089567Y1506243I2784J-2784D01*
G01X1100225Y1518532D02*
X1090720Y1509027D01*
G01D02*
G03X1089567Y1506243I2784J-2784D01*
G01X1100225Y1518532D02*
X1090720Y1509027D01*
G01X1061980Y1518532D02*
G03X1059196Y1519685I-2784J-2784D01*
G01X1061980Y1518532D02*
G03X1059196Y1519685I-2784J-2784D01*
G01X1071485Y1509027D02*
X1061980Y1518532D01*
G01X1072638Y1506243D02*
G03X1071485Y1509027I-3937J0D01*
G01X1072638Y1506243D02*
G03X1071485Y1509027I-3937J0D01*
G01X1061980Y1518532D02*
X1071485Y1509027D01*
G01X1216535Y54331D02*
G03X1224409I3937J0D01*
G01X1216535D02*
Y181890D01*
G01Y54331D02*
Y181890D01*
G01Y54331D02*
G03X1224409I3937J0D01*
G01Y23622D02*
G03X1216535I-3937J0D01*
G01X1224409D02*
G03X1216535I-3937J0D01*
G01X1212598Y0D02*
G03X1216535Y3937I0J3937D01*
G01D02*
Y23622D01*
G01X1212598Y0D02*
G03X1216535Y3937I0J3937D01*
G01X1224409D02*
G03X1228346Y0I3937J0D01*
G01X1224409Y185827D02*
Y3937D01*
G01X1216535D02*
Y23622D01*
G01X1224409Y3937D02*
G03X1228346Y0I3937J0D01*
G01X1224409Y3937D02*
Y185827D01*
G01X1228346Y0D02*
X1930906D01*
G01X1228346D02*
X1930906D01*
G01X1224409Y185827D02*
G03X1220472Y189764I-3937J0D01*
G01X1224409Y185827D02*
G03X1220472Y189764I-3937J0D01*
G01X1164984Y383609D02*
G03X1198795I16906J-13530D01*
G01X1164984D02*
G03X1198795I16906J-13530D01*
G01X1191870Y396741D02*
G03X1198795Y383610I37662J11471D01*
G01X1191870Y396741D02*
G03X1198795Y383609I37663J11469D01*
G01X1191870Y396741D02*
G03X1171909I-9980J-3040D01*
G01X1164984Y383610D02*
G03X1171909Y396741I-30737J24602D01*
G01X1191870D02*
G03X1171909I-9980J-3040D01*
G01X1164984Y383609D02*
G03X1171909Y396741I-30737J24601D01*
G01X1164984Y974161D02*
G03X1198795I16906J-13531D01*
G01X1164984D02*
G03X1198795I16906J-13531D01*
G01X1191870Y987292D02*
G03X1198795Y974161I37662J11471D01*
G01X1191870Y987292D02*
G03X1198795Y974161I37662J11471D01*
G01X1191870Y987292D02*
G03X1171909I-9980J-3040D01*
G01X1164984Y974161D02*
G03X1171909Y987292I-30737J24602D01*
G01X1191870D02*
G03X1171909I-9980J-3040D01*
G01X1164984Y974161D02*
G03X1171909Y987292I-30737J24601D01*
G01X1240748Y1505118D02*
G03X1244685Y1509055I0J3937D01*
G01X1240748Y1505118D02*
G03X1244685Y1509055I0J3937D01*
G01X1211220Y1515748D02*
G03X1207283Y1519685I-3937J0D01*
G01X1211220Y1515748D02*
G03X1207283Y1519685I-3937J0D01*
G01X1211220Y1509055D02*
Y1515748D01*
G01Y1509055D02*
G03X1215157Y1505118I3937J0D01*
G01X1240748D02*
X1215157D01*
G01X1211220Y1509055D02*
G03X1215157Y1505118I3937J0D01*
G01D02*
X1240748D01*
G01X1211220Y1515748D02*
Y1509055D01*
G01X1311851Y277843D02*
G03X1318775Y264712I37663J11469D01*
G01X1311850Y277843D02*
G03X1318776Y264712I37661J11473D01*
G01X1311851Y277843D02*
G03X1291890I-9980J-3040D01*
G01X1284965Y264712D02*
G03X1291890Y277843I-30737J24602D01*
G01X1311850D02*
G03X1291890I-9980J-3040D01*
G01X1284965Y264712D02*
G03X1291890Y277843I-30737J24602D01*
G01X1284965Y264712D02*
G03X1318775I16905J-13531D01*
G01X1284965D02*
G03X1318776I16906J-13531D01*
G01X1311851Y730599D02*
G03X1318775Y717468I37663J11469D01*
G01X1311850Y730599D02*
G03X1318776Y717468I37661J11473D01*
G01X1311851Y730599D02*
G03X1291890I-9980J-3040D01*
G01X1284965Y717468D02*
G03X1291891Y730599I-30736J24604D01*
G01X1311850D02*
G03X1291890I-9980J-3040D01*
G01X1284965Y717468D02*
G03X1291890Y730599I-30737J24602D01*
G01X1284965Y717468D02*
G03X1318775I16905J-13531D01*
G01X1284965D02*
G03X1318776I16906J-13531D01*
G01X1284965Y1170224D02*
G03X1318775I16905J-13531D01*
G01X1284965D02*
G03X1318776I16906J-13531D01*
G01X1311851Y1183355D02*
G03X1318775Y1170224I37663J11469D01*
G01X1311850Y1183355D02*
G03X1318776Y1170224I37661J11473D01*
G01X1311851Y1183355D02*
G03X1291890I-9980J-3040D01*
G01X1311850D02*
G03X1291890I-9980J-3040D01*
G01X1284965Y1170224D02*
G03X1291890Y1183355I-30737J24602D01*
G01X1284965Y1170224D02*
G03X1291890Y1183355I-30737J24602D01*
G01X1248622Y1519685D02*
G03X1244685Y1515748I0J-3937D01*
G01X1427953Y1519685D02*
X1248622D01*
G01D02*
G03X1244685Y1515748I0J-3937D01*
G01X1427953Y1519685D02*
X1248622D01*
G01X1244685Y1515748D02*
Y1509055D01*
G01Y1515748D02*
Y1509055D01*
G01X1431890Y1515748D02*
G03X1427953Y1519685I-3937J0D01*
G01X1431890Y1515748D02*
G03X1427953Y1519685I-3937J0D01*
G01X1431890Y1500000D02*
Y1515748D01*
G01Y1500000D02*
G03X1435827Y1496063I3937J0D01*
G01X1431890Y1500000D02*
G03X1435827Y1496063I3937J0D01*
G01X1431890Y1515748D02*
Y1500000D01*
G01X1532996Y264712D02*
G03X1566807I16906J-13531D01*
G01X1532996D02*
G03X1566807I16906J-13531D01*
G01X1532996Y717468D02*
G03X1566807I16906J-13531D01*
G01X1532996D02*
G03X1566807I16906J-13531D01*
G01X1532996Y1170224D02*
G03X1566807I16906J-13531D01*
G01X1532996D02*
G03X1566807I16906J-13531D01*
G01X1469685Y1503937D02*
G03Y1496063I0J-3937D01*
G01X1451575D02*
G03Y1503937I0J3937D01*
G01X1606693D02*
X1469685D01*
G01X1606693D02*
X1469685D01*
G01D02*
G03Y1496063I0J-3937D01*
G01X1451575D02*
G03Y1503937I0J3937D01*
G01X1443701Y1519685D02*
G03X1439764Y1515748I0J-3937D01*
G01X1443701Y1519685D02*
X1632677D01*
G01X1443701D02*
G03X1439764Y1515748I0J-3937D01*
G01X1443701Y1519685D02*
X1632677D01*
G01X1451575Y1503937D02*
X1439764D01*
G01Y1515748D02*
Y1503937D01*
G01X1451575D02*
X1439764D01*
G01X1640551Y1496063D02*
X1435827D01*
G01X1439764Y1515748D02*
Y1503937D01*
G01X1640551Y1496063D02*
X1435827D01*
G01X1559882Y277843D02*
G03X1566807Y264712I37662J11471D01*
G01X1559882Y277843D02*
G03X1539921I-9980J-3040D01*
G01X1559882D02*
G03X1566807Y264712I37662J11471D01*
G01X1559882Y277843D02*
G03X1539921I-9980J-3040D01*
G01X1532996Y264712D02*
G03X1539921Y277843I-30737J24602D01*
G01X1532996Y264712D02*
G03X1539921Y277843I-30737J24602D01*
G01X1559882Y730599D02*
G03X1566807Y717468I37662J11471D01*
G01X1559882Y730599D02*
G03X1539921I-9980J-3040D01*
G01X1559882D02*
G03X1566807Y717468I37662J11471D01*
G01X1559882Y730599D02*
G03X1539921I-9980J-3040D01*
G01X1532996Y717468D02*
G03X1539921Y730599I-30737J24601D01*
G01X1532996Y717468D02*
G03X1539921Y730599I-30737J24601D01*
G01X1559882Y1183355D02*
G03X1539921I-9980J-3040D01*
G01X1559882D02*
G03X1539921I-9980J-3040D01*
G01X1559882D02*
G03X1566807Y1170224I37662J11471D01*
G01X1559882Y1183355D02*
G03X1566807Y1170224I37662J11471D01*
G01X1532996D02*
G03X1539921Y1183355I-30737J24602D01*
G01X1532996Y1170224D02*
G03X1539921Y1183355I-30737J24601D01*
G01X1636614Y1503937D02*
X1624803D01*
G01X1636614D02*
X1624803D01*
G01D02*
G03Y1496063I0J-3937D01*
G01X1606693D02*
G03Y1503937I0J3937D01*
G01X1624803D02*
G03Y1496063I0J-3937D01*
G01X1606693D02*
G03Y1503937I0J3937D01*
G01X1636614Y1515748D02*
G03X1632677Y1519685I-3937J0D01*
G01X1636614Y1515748D02*
G03X1632677Y1519685I-3937J0D01*
G01X1648425D02*
G03X1644488Y1515748I0J-3937D01*
G01X1827756Y1519685D02*
X1648425D01*
G01D02*
G03X1644488Y1515748I0J-3937D01*
G01X1827756Y1519685D02*
X1648425D01*
G01X1636614Y1515748D02*
Y1503937D01*
G01X1640551Y1496063D02*
G03X1644488Y1500000I0J3937D01*
G01Y1515748D02*
Y1500000D01*
G01X1636614Y1515748D02*
Y1503937D01*
G01X1640551Y1496063D02*
G03X1644488Y1500000I0J3937D01*
G01Y1515748D02*
Y1500000D01*
G01X1807914Y277843D02*
G03X1814838Y264712I37663J11469D01*
G01X1807913Y277843D02*
G03X1814839Y264712I37661J11473D01*
G01X1807914Y277843D02*
G03X1787953I-9980J-3040D01*
G01X1781028Y264712D02*
G03X1787953Y277843I-30737J24602D01*
G01X1807913D02*
G03X1787953I-9980J-3040D01*
G01X1781028Y264712D02*
G03X1787953Y277843I-30737J24602D01*
G01X1781028Y264712D02*
G03X1814839I16906J-13531D01*
G01X1781028D02*
G03X1814839I16906J-13531D01*
G01X1807914Y730599D02*
G03X1814838Y717468I37663J11469D01*
G01X1807913Y730599D02*
G03X1814839Y717468I37661J11473D01*
G01X1807914Y730599D02*
G03X1787953I-9980J-3040D01*
G01X1781028Y717468D02*
G03X1787954Y730599I-30736J24604D01*
G01X1807913D02*
G03X1787953I-9980J-3040D01*
G01X1781028Y717468D02*
G03X1787953Y730599I-30737J24602D01*
G01X1781028Y717468D02*
G03X1814838I16905J-13531D01*
G01X1781028D02*
G03X1814839I16906J-13531D01*
G01X1781028Y1170224D02*
G03X1814838I16905J-13531D01*
G01X1781028D02*
G03X1814839I16906J-13531D01*
G01X1807914Y1183355D02*
G03X1814838Y1170224I37662J11468D01*
G01X1807913Y1183355D02*
G03X1814839Y1170224I37661J11473D01*
G01X1807914Y1183355D02*
G03X1787953I-9980J-3040D01*
G01X1807913D02*
G03X1787953I-9980J-3040D01*
G01X1781028Y1170224D02*
G03X1787953Y1183355I-30737J24602D01*
G01X1781028Y1170224D02*
G03X1787953Y1183355I-30737J24602D01*
G01X1869094Y1519685D02*
G03X1865157Y1515748I0J-3937D01*
G01X1919094Y1519685D02*
X1869094D01*
G01D02*
G03X1865157Y1515748I0J-3937D01*
G01X1919094Y1519685D02*
X1869094D01*
G01X1865157Y1515748D02*
Y1509055D01*
G01Y1515748D02*
Y1509055D01*
G01X1861220Y1505118D02*
X1835630D01*
G01X1861220D02*
G03X1865157Y1509055I0J3937D01*
G01X1861220Y1505118D02*
G03X1865157Y1509055I0J3937D01*
G01X1835630Y1505118D02*
X1861220D01*
G01X1831693Y1515748D02*
G03X1827756Y1519685I-3937J0D01*
G01X1831693Y1515748D02*
G03X1827756Y1519685I-3937J0D01*
G01X1831693Y1509055D02*
Y1515748D01*
G01Y1509055D02*
G03X1835630Y1505118I3937J0D01*
G01X1831693Y1509055D02*
G03X1835630Y1505118I3937J0D01*
G01X1831693Y1515748D02*
Y1509055D01*
G01X1930906Y0D02*
G03X1934843Y3937I0J3937D01*
G01X1930906Y0D02*
G03X1934843Y3937I0J3937D01*
G01D02*
Y1456693D01*
G01Y3937D02*
Y1456693D01*
G01X1930906Y1460630D02*
X1926969D01*
G01X1934843Y1456693D02*
G03X1930906Y1460630I-3937J0D01*
G01X1934843Y1456693D02*
G03X1930906Y1460630I-3937J0D01*
G01D02*
X1926969D01*
G01X1923031Y1515748D02*
G03X1919094Y1519685I-3937J0D01*
G01X1923031Y1515748D02*
G03X1919094Y1519685I-3937J0D01*
G01X1923031Y1464567D02*
Y1515748D01*
G01Y1464567D02*
G03X1926969Y1460630I3937J0D01*
G01X1923031Y1464567D02*
G03X1926969Y1460630I3937J0D01*
G01X1923031Y1515748D02*
Y1464567D01*
G54D12*
G01X856584Y279346D02*
X855846D01*
G01X856584Y280496D02*
X855846D01*
G01X859236Y281998D02*
G02X856584Y279346I-2652J0D01*
G01X858086Y281998D02*
G02X856584Y280496I-1502J0D01*
G01X859236Y322183D02*
Y281998D01*
G01X858086Y322524D02*
Y281998D01*
G01X856584Y280496D02*
X855846D01*
G01X856584Y279346D02*
X855846D01*
G01X858086Y281998D02*
G02X856584Y280496I-1502J0D01*
G01X859236Y281998D02*
G02X856584Y279346I-2652J0D01*
G01X858086Y322524D02*
Y281998D01*
G01X859236Y322183D02*
Y281998D01*
G01X849498Y260448D02*
X848760D01*
G01X849498Y261598D02*
X848760D01*
G01X852150Y263100D02*
G02X849498Y260448I-2652J0D01*
G01X851000Y263100D02*
G02X849498Y261598I-1502J0D01*
G01X852150Y321951D02*
Y263100D01*
G01X851000Y322292D02*
Y263100D01*
G01X849498Y261598D02*
X848760D01*
G01X849498Y260448D02*
X848760D01*
G01X851000Y263100D02*
G02X849498Y261598I-1502J0D01*
G01X852150Y263100D02*
G02X849498Y260448I-2652J0D01*
G01X851000Y322292D02*
Y263100D01*
G01X852150Y321951D02*
Y263100D01*
G01X842411Y279346D02*
X841673D01*
G01X842411Y280496D02*
X841673D01*
G01X845063Y281998D02*
G02X842411Y279346I-2652J0D01*
G01X843913Y281998D02*
G02X842411Y280496I-1502J0D01*
G01X845063Y321687D02*
Y281998D01*
G01X843913Y322028D02*
Y281998D01*
G01X842411Y280496D02*
X841673D01*
G01X842411Y279346D02*
X841673D01*
G01X843913Y281998D02*
G02X842411Y280496I-1502J0D01*
G01X845063Y281998D02*
G02X842411Y279346I-2652J0D01*
G01X843913Y322028D02*
Y281998D01*
G01X845063Y321687D02*
Y281998D01*
G01X835325Y260448D02*
X834587D01*
G01X835325Y261598D02*
X834587D01*
G01X837977Y263100D02*
G02X835325Y260448I-2652J0D01*
G01X836827Y263100D02*
G02X835325Y261598I-1502J0D01*
G01X837977Y324038D02*
Y263100D01*
G01X836827Y324379D02*
Y263100D01*
G01X835325Y261598D02*
X834587D01*
G01X835325Y260448D02*
X834587D01*
G01X836827Y263100D02*
G02X835325Y261598I-1502J0D01*
G01X837977Y263100D02*
G02X835325Y260448I-2652J0D01*
G01X836827Y324379D02*
Y263100D01*
G01X837977Y324038D02*
Y263100D01*
G01X829100Y279346D02*
X827500D01*
G01X829100Y280496D02*
X827500D01*
G01X830890Y281136D02*
G02X829100Y279346I-1790J0D01*
G01X829740Y281136D02*
G02X829100Y280496I-640J0D01*
G01X830890Y325814D02*
Y281136D01*
G01X829740Y326155D02*
Y281136D01*
G01X829100Y280496D02*
X827500D01*
G01X829100Y279346D02*
X827500D01*
G01X829740Y281136D02*
G02X829100Y280496I-640J0D01*
G01X830890Y281136D02*
G02X829100Y279346I-1790J0D01*
G01X829740Y326155D02*
Y281136D01*
G01X830890Y325814D02*
Y281136D01*
G01X931675Y433736D02*
X859236Y322183D01*
G01X873182Y345772D02*
X858086Y322524D01*
G01X873182Y345772D02*
X858086Y322524D01*
G01X931675Y433736D02*
X859236Y322183D01*
G01X931675Y433736D02*
X859236Y322183D01*
G01X931675Y433736D02*
X859236Y322183D01*
G01X931675Y433736D02*
X859236Y322183D01*
G01X931675Y433736D02*
X859236Y322183D01*
G01X926937Y437149D02*
X852150Y321951D01*
G01X903243Y402766D02*
X851000Y322292D01*
G01X903243Y402766D02*
X851000Y322292D01*
G01X926937Y437149D02*
X852150Y321951D01*
G01X926937Y437149D02*
X852150Y321951D01*
G01X926937Y437149D02*
X852150Y321951D01*
G01X926937Y437149D02*
X852150Y321951D01*
G01X926937Y437149D02*
X852150Y321951D01*
G01X925133Y445020D02*
X845063Y321687D01*
G01X885368Y385882D02*
X843913Y322028D01*
G01X885368Y385882D02*
X843913Y322028D01*
G01X925133Y445020D02*
X845063Y321687D01*
G01X925133Y445020D02*
X845063Y321687D01*
G01X925133Y445020D02*
X845063Y321687D01*
G01X925133Y445020D02*
X845063Y321687D01*
G01X925133Y445020D02*
X845063Y321687D01*
G01X917380Y446322D02*
X837977Y324038D01*
G01X870450Y376161D02*
X836827Y324379D01*
G01X870450Y376161D02*
X836827Y324379D01*
G01X917380Y446322D02*
X837977Y324038D01*
G01X917380Y446322D02*
X837977Y324038D01*
G01X917380Y446322D02*
X837977Y324038D01*
G01X917380Y446322D02*
X837977Y324038D01*
G01X917380Y446322D02*
X837977Y324038D01*
G01X833699Y330139D02*
X830890Y325814D01*
G01X841324Y343995D02*
X829740Y326155D01*
G01X912616Y451674D02*
X833699Y330139D01*
G01X843720Y347685D02*
X842822Y346302D01*
G01X846117Y351376D02*
X845218Y349992D01*
G01X848513Y355066D02*
X847614Y353682D01*
G01X911784Y452506D02*
X850010Y357372D01*
G01X841324Y343995D02*
X829740Y326155D01*
G01X833699Y330139D02*
X830890Y325814D01*
G01X843720Y347685D02*
X842822Y346302D01*
G01X912616Y451674D02*
X833699Y330139D01*
G01X846117Y351376D02*
X845218Y349992D01*
G01X912616Y451674D02*
X833699Y330139D01*
G01X848513Y355066D02*
X847614Y353682D01*
G01X912616Y451674D02*
X833699Y330139D01*
G01X911784Y452506D02*
X850010Y357372D01*
G01X912616Y451674D02*
X833699Y330139D01*
G01X877844Y260448D02*
X877106D01*
G01X877844Y261598D02*
X877106D01*
G01X880496Y263100D02*
G02X877844Y260448I-2652J0D01*
G01X879346Y263100D02*
G02X877844Y261598I-1502J0D01*
G01X880496Y301960D02*
Y263100D01*
G01X879346Y302081D02*
Y263100D01*
G01X877844Y261598D02*
X877106D01*
G01X877844Y260448D02*
X877106D01*
G01X879346Y263100D02*
G02X877844Y261598I-1502J0D01*
G01X880496Y263100D02*
G02X877844Y260448I-2652J0D01*
G01X879346Y302081D02*
Y263100D01*
G01X880496Y301960D02*
Y263100D01*
G01X870758Y279346D02*
X870020D01*
G01X870758Y280496D02*
X870020D01*
G01X873410Y281998D02*
G02X870758Y279346I-2652J0D01*
G01X872260Y281998D02*
G02X870758Y280496I-1502J0D01*
G01X873410Y307546D02*
Y281998D01*
G01X872260Y307657D02*
Y281998D01*
G01X870758Y280496D02*
X870020D01*
G01X870758Y279346D02*
X870020D01*
G01X872260Y281998D02*
G02X870758Y280496I-1502J0D01*
G01X873410Y281998D02*
G02X870758Y279346I-2652J0D01*
G01X872260Y307657D02*
Y281998D01*
G01X873410Y307546D02*
Y281998D01*
G01X863671Y260448D02*
X862933D01*
G01X863671Y261598D02*
X862933D01*
G01X866323Y263100D02*
G02X863671Y260448I-2652J0D01*
G01X865173Y263100D02*
G02X863671Y261598I-1502J0D01*
G01X866323Y313063D02*
Y263100D01*
G01X865173Y313184D02*
Y263100D01*
G01X863671Y261598D02*
X862933D01*
G01X863671Y260448D02*
X862933D01*
G01X865173Y263100D02*
G02X863671Y261598I-1502J0D01*
G01X866323Y263100D02*
G02X863671Y260448I-2652J0D01*
G01X865173Y313184D02*
Y263100D01*
G01X866323Y313063D02*
Y263100D01*
G01X888515Y339910D02*
X880496Y301960D01*
G01X887434Y340357D02*
X879346Y302081D01*
G01X909989Y372985D02*
X888515Y339910D01*
G01X898287Y357074D02*
X887434Y340357D01*
G01X901751Y362410D02*
X898287Y357074D01*
G01X909157Y373817D02*
X901751Y362410D01*
G01X1124338Y512281D02*
X909989Y372985D01*
G01X912887Y376241D02*
X909157Y373817D01*
G01X916643Y378682D02*
X915260Y377783D01*
G01X887434Y340357D02*
X879346Y302081D01*
G01X888515Y339910D02*
X880496Y301960D01*
G01X898287Y357074D02*
X887434Y340357D01*
G01X909989Y372985D02*
X888515Y339910D01*
G01X901751Y362410D02*
X898287Y357074D01*
G01X909989Y372985D02*
X888515Y339910D01*
G01X909157Y373817D02*
X901751Y362410D01*
G01X909989Y372985D02*
X888515Y339910D01*
G01X912887Y376241D02*
X909157Y373817D01*
G01X1124338Y512281D02*
X909989Y372985D01*
G01X916643Y378682D02*
X915260Y377783D01*
G01X1124338Y512281D02*
X909989Y372985D01*
G01X1124338Y512281D02*
X909989Y372985D01*
G01X1124338Y512281D02*
X909989Y372985D01*
G01X1124338Y512281D02*
X909989Y372985D01*
G01X1124338Y512281D02*
X909989Y372985D01*
G01X878089Y331620D02*
X873410Y307546D01*
G01X873009Y311512D02*
X872260Y307657D01*
G01X873617Y314644D02*
X873009Y311512D01*
G01X874438Y318866D02*
X874123Y317246D01*
G01X875293Y323264D02*
X874978Y321644D01*
G01X876147Y327661D02*
X875833Y326042D01*
G01X877002Y332059D02*
X876656Y330283D01*
G01X937548Y423140D02*
X878089Y331620D01*
G01X936716Y423972D02*
X877002Y332059D01*
G01X873009Y311512D02*
X872260Y307657D01*
G01X878089Y331620D02*
X873410Y307546D01*
G01X873617Y314644D02*
X873009Y311512D01*
G01X878089Y331620D02*
X873410Y307546D01*
G01X874438Y318866D02*
X874123Y317246D01*
G01X878089Y331620D02*
X873410Y307546D01*
G01X875293Y323264D02*
X874978Y321644D01*
G01X878089Y331620D02*
X873410Y307546D01*
G01X876147Y327661D02*
X875833Y326042D01*
G01X878089Y331620D02*
X873410Y307546D01*
G01X877002Y332059D02*
X876656Y330283D01*
G01X878089Y331620D02*
X873410Y307546D01*
G01X936716Y423972D02*
X877002Y332059D01*
G01X937548Y423140D02*
X878089Y331620D01*
G01X869477Y327911D02*
X866323Y313063D01*
G01X868396Y328359D02*
X865173Y313184D01*
G01X933807Y426931D02*
X869477Y327911D01*
G01X874627Y337950D02*
X868396Y328359D01*
G01X877024Y341640D02*
X876125Y340256D01*
G01X879421Y345330D02*
X878522Y343946D01*
G01X881818Y349020D02*
X880919Y347636D01*
G01X932975Y427763D02*
X883316Y351326D01*
G01X868396Y328359D02*
X865173Y313184D01*
G01X869477Y327911D02*
X866323Y313063D01*
G01X874627Y337950D02*
X868396Y328359D01*
G01X933807Y426931D02*
X869477Y327911D01*
G01X877024Y341640D02*
X876125Y340256D01*
G01X933807Y426931D02*
X869477Y327911D01*
G01X879421Y345330D02*
X878522Y343946D01*
G01X933807Y426931D02*
X869477Y327911D01*
G01X881818Y349020D02*
X880919Y347636D01*
G01X933807Y426931D02*
X869477Y327911D01*
G01X932975Y427763D02*
X883316Y351326D01*
G01X933807Y426931D02*
X869477Y327911D01*
G01X875578Y349462D02*
X874680Y348078D01*
G01X877975Y353152D02*
X877076Y351769D01*
G01X880371Y356843D02*
X879472Y355459D01*
G01X930843Y434568D02*
X881869Y359149D01*
G01X875578Y349462D02*
X874680Y348078D01*
G01X877975Y353152D02*
X877076Y351769D01*
G01X880371Y356843D02*
X879472Y355459D01*
G01X930843Y434568D02*
X881869Y359149D01*
G01X872846Y379852D02*
X871948Y378468D01*
G01X872846Y379852D02*
X871948Y378468D01*
G01X920400Y381123D02*
X919016Y380224D01*
G01X924156Y383564D02*
X922773Y382665D01*
G01X931114Y388086D02*
X926456Y385060D01*
G01X1123610Y513181D02*
X931114Y388086D01*
G01X920400Y381123D02*
X919016Y380224D01*
G01X924156Y383564D02*
X922773Y382665D01*
G01X931114Y388086D02*
X926456Y385060D01*
G01X1123610Y513181D02*
X931114Y388086D01*
G01X1091357Y523025D02*
X937548Y423140D01*
G01X1091016Y524175D02*
X936716Y423972D01*
G01X1091016Y524175D02*
X936716Y423972D01*
G01X1091357Y523025D02*
X937548Y423140D01*
G01X1092691Y530112D02*
X933807Y426931D01*
G01X1092350Y531262D02*
X932975Y427763D01*
G01X1092350Y531262D02*
X932975Y427763D01*
G01X1092691Y530112D02*
X933807Y426931D01*
G01X1090987Y537199D02*
X931675Y433736D01*
G01X1090646Y538349D02*
X930843Y434568D01*
G01X1090646Y538349D02*
X930843Y434568D01*
G01X1090987Y537199D02*
X931675Y433736D01*
G01X905639Y406457D02*
X904741Y405073D01*
G01X908035Y410147D02*
X907137Y408763D01*
G01X910431Y413838D02*
X909532Y412454D01*
G01X926105Y437981D02*
X911928Y416144D01*
G01X1091913Y544285D02*
X926937Y437149D01*
G01X1091572Y545435D02*
X926105Y437981D01*
G01X905639Y406457D02*
X904741Y405073D01*
G01X908035Y410147D02*
X907137Y408763D01*
G01X910431Y413838D02*
X909532Y412454D01*
G01X926105Y437981D02*
X911928Y416144D01*
G01X1091572Y545435D02*
X926105Y437981D01*
G01X1091913Y544285D02*
X926937Y437149D01*
G01X887764Y389573D02*
X886866Y388189D01*
G01X890160Y393263D02*
X889262Y391879D01*
G01X892556Y396954D02*
X891657Y395570D01*
G01X924301Y445852D02*
X894053Y399260D01*
G01X1088892Y551372D02*
X925133Y445020D01*
G01X1088551Y552522D02*
X924301Y445852D01*
G01X887764Y389573D02*
X886866Y388189D01*
G01X890160Y393263D02*
X889262Y391879D01*
G01X892556Y396954D02*
X891657Y395570D01*
G01X924301Y445852D02*
X894053Y399260D01*
G01X1088551Y552522D02*
X924301Y445852D01*
G01X1088892Y551372D02*
X925133Y445020D01*
G01X875243Y383542D02*
X874344Y382158D01*
G01X877639Y387232D02*
X876740Y385848D01*
G01X916548Y447154D02*
X879136Y389539D01*
G01X1090062Y558458D02*
X917380Y446322D01*
G01X1089721Y559608D02*
X916548Y447154D01*
G01X875243Y383542D02*
X874344Y382158D01*
G01X877639Y387232D02*
X876740Y385848D01*
G01X916548Y447154D02*
X879136Y389539D01*
G01X1089721Y559608D02*
X916548Y447154D01*
G01X1090062Y558458D02*
X917380Y446322D01*
G01X1000276Y508609D02*
X912616Y451674D01*
G01X999649Y509574D02*
X911784Y452506D01*
G01X999649Y509574D02*
X911784Y452506D01*
G01X1000276Y508609D02*
X912616Y451674D01*
G01X1044108Y537076D02*
X1000276Y508609D01*
G01X1087599Y566695D02*
X999649Y509574D01*
G01X1087940Y565545D02*
X1044108Y537076D01*
G01X1087599Y566695D02*
X999649Y509574D01*
G01X1087599Y566695D02*
X999649Y509574D01*
G01X1044108Y537076D02*
X1000276Y508609D01*
G01X1087940Y565545D02*
X1044108Y537076D01*
G01X1127097Y515037D02*
X1124338Y512281D01*
G01X1125947Y515514D02*
X1123610Y513181D01*
G01X1127097Y519194D02*
Y515037D01*
G01X1125947Y519194D02*
Y515514D01*
G01D02*
X1123610Y513181D01*
G01X1127097Y515037D02*
X1124338Y512281D01*
G01X1125947Y519194D02*
Y515514D01*
G01X1127097Y519194D02*
Y515037D01*
G01X1128479Y523025D02*
X1091357D01*
G01X1128479Y524175D02*
X1091016D01*
G01X1131034Y525580D02*
G02X1128479Y523025I-2555J0D01*
G01X1129884Y525580D02*
G02X1128479Y524175I-1405J0D01*
G01X1131034Y526280D02*
Y525580D01*
G01X1129884Y526280D02*
Y525580D01*
G01X1128479Y524175D02*
X1091016D01*
G01X1128479Y523025D02*
X1091357D01*
G01X1129884Y525580D02*
G02X1128479Y524175I-1405J0D01*
G01X1131034Y525580D02*
G02X1128479Y523025I-2555J0D01*
G01X1129884Y526280D02*
Y525580D01*
G01X1131034Y526280D02*
Y525580D01*
G01X1124542Y530112D02*
X1092691D01*
G01X1124542Y531262D02*
X1092350D01*
G01X1127097Y532667D02*
G02X1124542Y530112I-2555J0D01*
G01X1125947Y532667D02*
G02X1124542Y531262I-1405J0D01*
G01X1127097Y533367D02*
Y532667D01*
G01X1125947Y533367D02*
Y532667D01*
G01X1124542Y531262D02*
X1092350D01*
G01X1124542Y530112D02*
X1092691D01*
G01X1125947Y532667D02*
G02X1124542Y531262I-1405J0D01*
G01X1127097Y532667D02*
G02X1124542Y530112I-2555J0D01*
G01X1125947Y533367D02*
Y532667D01*
G01X1127097Y533367D02*
Y532667D01*
G01X1128479Y537199D02*
X1090987D01*
G01X1128479Y538349D02*
X1090646D01*
G01X1131034Y539754D02*
G02X1128479Y537199I-2555J0D01*
G01X1129884Y539754D02*
G02X1128479Y538349I-1405J0D01*
G01X1131034Y540454D02*
Y539754D01*
G01X1129884Y540454D02*
Y539754D01*
G01X1128479Y538349D02*
X1090646D01*
G01X1128479Y537199D02*
X1090987D01*
G01X1129884Y539754D02*
G02X1128479Y538349I-1405J0D01*
G01X1131034Y539754D02*
G02X1128479Y537199I-2555J0D01*
G01X1129884Y540454D02*
Y539754D01*
G01X1131034Y540454D02*
Y539754D01*
G01X1124542Y544285D02*
X1091913D01*
G01X1124542Y545435D02*
X1091572D01*
G01X1127097Y546840D02*
G02X1124542Y544285I-2555J0D01*
G01X1125947Y546840D02*
G02X1124542Y545435I-1405J0D01*
G01X1127097Y547540D02*
Y546840D01*
G01X1125947Y547540D02*
Y546840D01*
G01X1124542Y545435D02*
X1091572D01*
G01X1124542Y544285D02*
X1091913D01*
G01X1125947Y546840D02*
G02X1124542Y545435I-1405J0D01*
G01X1127097Y546840D02*
G02X1124542Y544285I-2555J0D01*
G01X1125947Y547540D02*
Y546840D01*
G01X1127097Y547540D02*
Y546840D01*
G01X1128479Y551372D02*
X1088892D01*
G01X1128479Y552522D02*
X1088551D01*
G01X1131034Y553927D02*
G02X1128479Y551372I-2555J0D01*
G01X1129884Y553927D02*
G02X1128479Y552522I-1405J0D01*
G01X1131034Y554627D02*
Y553927D01*
G01X1129884Y554627D02*
Y553927D01*
G01X1128479Y552522D02*
X1088551D01*
G01X1128479Y551372D02*
X1088892D01*
G01X1129884Y553927D02*
G02X1128479Y552522I-1405J0D01*
G01X1131034Y553927D02*
G02X1128479Y551372I-2555J0D01*
G01X1129884Y554627D02*
Y553927D01*
G01X1131034Y554627D02*
Y553927D01*
G01X1124542Y558458D02*
X1090062D01*
G01X1124542Y559608D02*
X1089721D01*
G01X1127097Y561013D02*
G02X1124542Y558458I-2555J0D01*
G01X1125947Y561013D02*
G02X1124542Y559608I-1405J0D01*
G01X1127097Y561713D02*
Y561013D01*
G01X1125947Y561713D02*
Y561013D01*
G01X1124542Y559608D02*
X1089721D01*
G01X1124542Y558458D02*
X1090062D01*
G01X1125947Y561013D02*
G02X1124542Y559608I-1405J0D01*
G01X1127097Y561013D02*
G02X1124542Y558458I-2555J0D01*
G01X1125947Y561713D02*
Y561013D01*
G01X1127097Y561713D02*
Y561013D01*
G01X1128479Y565545D02*
X1087940D01*
G01X1128479Y566695D02*
X1087599D01*
G01X1131034Y568100D02*
G02X1128479Y565545I-2555J0D01*
G01X1129884Y568100D02*
G02X1128479Y566695I-1405J0D01*
G01X1131034Y568800D02*
Y568100D01*
G01X1129884Y568800D02*
Y568100D01*
G01X1128479Y566695D02*
X1087599D01*
G01X1128479Y565545D02*
X1087940D01*
G01X1129884Y568100D02*
G02X1128479Y566695I-1405J0D01*
G01X1131034Y568100D02*
G02X1128479Y565545I-2555J0D01*
G01X1129884Y568800D02*
Y568100D01*
G01X1131034Y568800D02*
Y568100D01*
G54D13*
G01X136485Y74481D02*
X128463D01*
G01X136880Y73156D02*
X128463D01*
G01X160351Y90057D02*
X136485Y74481D01*
G01X205843Y118165D02*
X136880Y73156D01*
G01X164145Y92533D02*
X162951Y91754D01*
G01X205843Y118165D02*
X136880Y73156D01*
G01X205843Y118165D02*
X136880Y73156D01*
G01D02*
X128463D01*
G01X136485Y74481D02*
X128463D01*
G01X205843Y118165D02*
X136880Y73156D01*
G01X160351Y90057D02*
X136485Y74481D01*
G01X164145Y92533D02*
X162951Y91754D01*
G01X167938Y95009D02*
X166745Y94230D01*
G01X239698Y141843D02*
X170538Y96706D01*
G01X167938Y95009D02*
X166745Y94230D01*
G01X239698Y141843D02*
X170538Y96706D01*
G01X137366Y527237D02*
X128463D01*
G01X137701Y525912D02*
X128463D01*
G01X146661Y532252D02*
X137366Y527237D01*
G01X147291Y531086D02*
X137701Y525912D01*
G01X150648Y534403D02*
X149394Y533726D01*
G01X157997Y536861D02*
X147291Y531085D01*
G01X154635Y536554D02*
X153381Y535877D01*
G01X157997Y536861D02*
X147291Y531085D01*
G01X200004Y561031D02*
X157368Y538028D01*
G01X200466Y559774D02*
X157998Y536862D01*
G01X137701Y525912D02*
X128463D01*
G01X137366Y527237D02*
X128463D01*
G01X147291Y531086D02*
X137701Y525912D01*
G01X146661Y532252D02*
X137366Y527237D01*
G01X157997Y536861D02*
X147291Y531085D01*
G01X150648Y534403D02*
X149394Y533726D01*
G01X154635Y536554D02*
X153381Y535877D01*
G01X200466Y559774D02*
X157998Y536862D01*
G01X200004Y561031D02*
X157368Y538028D01*
G01X131868Y979993D02*
X128463D01*
G01X131742Y978668D02*
X128463D01*
G01X416589Y925350D02*
X131868Y979993D01*
G01X416879Y923945D02*
X131742Y978668D01*
G01D02*
X128463D01*
G01X131868Y979993D02*
X128463D01*
G01X416879Y923945D02*
X131742Y978668D01*
G01X416589Y925350D02*
X131868Y979993D01*
G01X266691Y74481D02*
X252675D01*
G01X267097Y73156D02*
X252675D01*
G01X269077Y76090D02*
X266691Y74481D01*
G01X270274Y75298D02*
X267097Y73156D01*
G01X271651Y77827D02*
X270485Y78053D01*
G01X360335Y136049D02*
X270275Y75300D01*
G01X272832Y78624D02*
X271651Y77827D01*
G01X360335Y136049D02*
X270275Y75300D01*
G01X275406Y80360D02*
X274240Y80587D01*
G01X360335Y136049D02*
X270275Y75300D01*
G01X276588Y81157D02*
X275406Y80360D01*
G01X360335Y136049D02*
X270275Y75300D01*
G01X279162Y82893D02*
X277996Y83120D01*
G01X360335Y136049D02*
X270275Y75300D01*
G01X359380Y137004D02*
X279162Y82893D01*
G01X360335Y136049D02*
X270275Y75300D01*
G01X267097Y73156D02*
X252675D01*
G01X266691Y74481D02*
X252675D01*
G01X270274Y75298D02*
X267097Y73156D01*
G01X269077Y76090D02*
X266691Y74481D01*
G01X360335Y136049D02*
X270275Y75300D01*
G01X271651Y77827D02*
X270485Y78053D01*
G01X272832Y78624D02*
X271651Y77827D01*
G01X275406Y80360D02*
X274240Y80587D01*
G01X276588Y81157D02*
X275406Y80360D01*
G01X279162Y82893D02*
X277996Y83120D01*
G01X359380Y137004D02*
X279162Y82893D01*
G01X240657Y140886D02*
X205843Y118165D01*
G01X329607Y280312D02*
X239698Y141843D01*
G01X330565Y279354D02*
X240657Y140886D01*
G01D02*
X205843Y118165D01*
G01X330565Y279354D02*
X240657Y140886D01*
G01X329607Y280312D02*
X239698Y141843D01*
G01X257195Y527237D02*
X252675D01*
G01X257430Y525912D02*
X252675D01*
G01X271087Y532286D02*
X257195Y527237D01*
G01X313292Y546217D02*
X257430Y525912D01*
G01X275269Y533807D02*
X273930Y533320D01*
G01X313292Y546217D02*
X257430Y525912D01*
G01X279451Y535327D02*
X278112Y534840D01*
G01X313292Y546217D02*
X257430Y525912D01*
G01X312697Y547411D02*
X282294Y536360D01*
G01X313292Y546217D02*
X257430Y525912D01*
G01D02*
X252675D01*
G01X257195Y527237D02*
X252675D01*
G01X313292Y546217D02*
X257430Y525912D01*
G01X271087Y532286D02*
X257195Y527237D01*
G01X275269Y533807D02*
X273930Y533320D01*
G01X279451Y535327D02*
X278112Y534840D01*
G01X312697Y547411D02*
X282294Y536360D01*
G01X796246Y687766D02*
X200004Y561031D01*
G01X796762Y686521D02*
X200466Y559774D01*
G01X796762Y686521D02*
X200466Y559774D01*
G01X796246Y687766D02*
X200004Y561031D01*
G01X255286Y979993D02*
X252675D01*
G01X255147Y978668D02*
X252675D01*
G01X384833Y955840D02*
X255286Y979993D01*
G01X729431Y890242D02*
X255147Y978668D01*
G01X729431Y890242D02*
X255147Y978668D01*
G01X729431Y890242D02*
X255147Y978668D01*
G01X729431Y890242D02*
X255147Y978668D01*
G01X729431Y890242D02*
X255147Y978668D01*
G01D02*
X252675D01*
G01X255286Y979993D02*
X252675D01*
G01X729431Y890242D02*
X255147Y978668D01*
G01X384833Y955840D02*
X255286Y979993D01*
G01X382158Y74481D02*
X376888D01*
G01X382401Y73156D02*
X376888D01*
G01X384327Y75304D02*
X382158Y74481D01*
G01X385203Y74218D02*
X382401Y73156D01*
G01X385936Y77785D02*
X384327Y75304D01*
G01X387182Y77269D02*
X385203Y74218D01*
G01X382401Y73156D02*
X376888D01*
G01X382158Y74481D02*
X376888D01*
G01X385203Y74218D02*
X382401Y73156D01*
G01X384327Y75304D02*
X382158Y74481D01*
G01X387182Y77269D02*
X385203Y74218D01*
G01X385936Y77785D02*
X384327Y75304D01*
G01X473263Y305843D02*
X359380Y137004D01*
G01X474211Y304878D02*
X360335Y136049D01*
G01X474211Y304878D02*
X360335Y136049D01*
G01X473263Y305843D02*
X359380Y137004D01*
G01X390479Y319845D02*
X329607Y280312D01*
G01X390995Y318600D02*
X330565Y279354D01*
G01X390995Y318600D02*
X330565Y279354D01*
G01X390479Y319845D02*
X329607Y280312D01*
G01X380840Y527237D02*
X376888D01*
G01X381081Y525912D02*
X376888D01*
G01X436964Y548295D02*
X380840Y527237D01*
G01X437565Y547105D02*
X381081Y525912D01*
G01D02*
X376888D01*
G01X380840Y527237D02*
X376888D01*
G01X437565Y547105D02*
X381081Y525912D01*
G01X436964Y548295D02*
X380840Y527237D01*
G01X354520Y574566D02*
X312697Y547411D01*
G01X355036Y573321D02*
X313292Y546217D01*
G01X355036Y573321D02*
X313292Y546217D01*
G01X354520Y574566D02*
X312697Y547411D01*
G01X775095Y663958D02*
X354520Y574566D01*
G01X775611Y662713D02*
X355036Y573321D01*
G01X775611Y662713D02*
X355036Y573321D01*
G01X775095Y663958D02*
X354520Y574566D01*
G01X380350Y979993D02*
X376888D01*
G01X380210Y978668D02*
X376888D01*
G01X555210Y942737D02*
X380350Y979993D01*
G01X749664Y899951D02*
X380210Y978668D01*
G01X749664Y899951D02*
X380210Y978668D01*
G01X749664Y899951D02*
X380210Y978668D01*
G01X749664Y899951D02*
X380210Y978668D01*
G01D02*
X376888D01*
G01X380350Y979993D02*
X376888D01*
G01X749664Y899951D02*
X380210Y978668D01*
G01X555210Y942737D02*
X380350Y979993D01*
G01X476138Y938817D02*
X384833Y955840D01*
G01X476138Y938817D02*
X384833Y955840D01*
G01X391924Y105947D02*
X385936Y77785D01*
G01X393169Y105431D02*
X387182Y77269D01*
G01X393169Y105431D02*
X387182Y77269D01*
G01X391924Y105947D02*
X385936Y77785D01*
G01X394339Y109669D02*
X391924Y105947D01*
G01X395451Y108946D02*
X393169Y105431D01*
G01X395909Y109650D02*
X395451Y108946D01*
G01X394567Y110019D02*
X394339Y109669D01*
G01X395451Y108946D02*
X393169Y105431D01*
G01X395909Y109650D02*
X395451Y108946D01*
G01X395710Y111779D02*
X394567Y110019D01*
G01X395909Y109650D02*
X395451Y108946D01*
G01X550228Y347327D02*
X395909Y109650D01*
G01X398134Y115511D02*
X397358Y114316D01*
G01X550228Y347327D02*
X395909Y109650D01*
G01X400557Y119243D02*
X399781Y118048D01*
G01X550228Y347327D02*
X395909Y109650D01*
G01X549270Y348285D02*
X402204Y121780D01*
G01X550228Y347327D02*
X395909Y109650D01*
G01X395451Y108946D02*
X393169Y105431D01*
G01X394339Y109669D02*
X391924Y105947D01*
G01X394567Y110019D02*
X394339Y109669D01*
G01X395909Y109650D02*
X395451Y108946D01*
G01X394339Y109669D02*
X391924Y105947D01*
G01X394567Y110019D02*
X394339Y109669D01*
G01X395710Y111779D02*
X394567Y110019D01*
G01X550228Y347327D02*
X395909Y109650D01*
G01X395710Y111779D02*
X394567Y110019D01*
G01X398134Y115511D02*
X397358Y114316D01*
G01X400557Y119243D02*
X399781Y118048D01*
G01X549270Y348285D02*
X402204Y121780D01*
G01X996226Y645448D02*
X473263Y305843D01*
G01X997184Y644490D02*
X474211Y304878D01*
G01X997184Y644490D02*
X474211Y304878D01*
G01X996226Y645448D02*
X473263Y305843D01*
G01X529288Y349350D02*
X390479Y319845D01*
G01X529804Y348105D02*
X390995Y318600D01*
G01X529804Y348105D02*
X390995Y318600D01*
G01X529288Y349350D02*
X390479Y319845D01*
G01X487998Y581442D02*
X436964Y548295D01*
G01X488514Y580197D02*
X437565Y547105D01*
G01X488514Y580197D02*
X437565Y547105D01*
G01X487998Y581442D02*
X436964Y548295D01*
G01X480513Y938001D02*
X479112Y938263D01*
G01X480513Y938001D02*
X479112Y938263D01*
G01X421038Y924496D02*
X419638Y924765D01*
G01X679607Y873513D02*
X416879Y923944D01*
G01X425486Y923642D02*
X424087Y923911D01*
G01X679607Y873513D02*
X416879Y923944D01*
G01X679594Y874865D02*
X428536Y923057D01*
G01X679607Y873513D02*
X416879Y923944D01*
G01X679607Y873513D02*
X416879Y923944D01*
G01X421038Y924496D02*
X419638Y924765D01*
G01X425486Y923642D02*
X424087Y923911D01*
G01X679594Y874865D02*
X428536Y923057D01*
G01X509450Y74481D02*
X501100D01*
G01X509643Y73156D02*
X501100D01*
G01X512646Y75431D02*
X509450Y74481D01*
G01X513492Y74300D02*
X509643Y73156D01*
G01X519921Y86637D02*
X512646Y75431D01*
G01X521166Y86121D02*
X513492Y74300D01*
G01X520812Y90828D02*
X519921Y86637D01*
G01X521663Y88457D02*
X521166Y86121D01*
G01X522108Y90552D02*
X521663Y88457D01*
G01X521702Y95016D02*
X520812Y90828D01*
G01X522554Y92647D02*
X522108Y90552D01*
G01X557801Y258483D02*
X522554Y92647D01*
G01X557801Y258483D02*
X522554Y92647D01*
G01X557801Y258483D02*
X522554Y92647D01*
G01X509643Y73156D02*
X501100D01*
G01X509450Y74481D02*
X501100D01*
G01X513492Y74300D02*
X509643Y73156D01*
G01X512646Y75431D02*
X509450Y74481D01*
G01X521166Y86121D02*
X513492Y74300D01*
G01X519921Y86637D02*
X512646Y75431D01*
G01X521663Y88457D02*
X521166Y86121D01*
G01X520812Y90828D02*
X519921Y86637D01*
G01X522108Y90552D02*
X521663Y88457D01*
G01X520812Y90828D02*
X519921Y86637D01*
G01X522554Y92647D02*
X522108Y90552D01*
G01X521702Y95016D02*
X520812Y90828D01*
G01X557801Y258483D02*
X522554Y92647D01*
G01X522644Y99447D02*
X522347Y98053D01*
G01X523585Y103878D02*
X523289Y102485D01*
G01X556556Y258999D02*
X524231Y106916D01*
G01X522644Y99447D02*
X522347Y98053D01*
G01X523585Y103878D02*
X523289Y102485D01*
G01X556556Y258999D02*
X524231Y106916D01*
G01X652801Y407203D02*
X556556Y258999D01*
G01X653759Y406245D02*
X557801Y258483D01*
G01X653759Y406245D02*
X557801Y258483D01*
G01X652801Y407203D02*
X556556Y258999D01*
G01X999448Y640609D02*
X549270Y348285D01*
G01X1000406Y639651D02*
X550228Y347327D01*
G01X1000406Y639651D02*
X550228Y347327D01*
G01X999448Y640609D02*
X549270Y348285D01*
G01X995361Y652014D02*
X529288Y349350D01*
G01X996319Y651056D02*
X529804Y348105D01*
G01X996319Y651056D02*
X529804Y348105D01*
G01X995361Y652014D02*
X529288Y349350D01*
G01X507834Y527237D02*
X501100D01*
G01X508180Y525912D02*
X501100D01*
G01X612268Y585626D02*
X507834Y527237D01*
G01X612740Y584371D02*
X508180Y525912D01*
G01D02*
X501100D01*
G01X507834Y527237D02*
X501100D01*
G01X612740Y584371D02*
X508180Y525912D01*
G01X612268Y585626D02*
X507834Y527237D01*
G01X523808Y589054D02*
X487998Y581442D01*
G01X506299Y583977D02*
X488514Y580197D01*
G01X524084Y587756D02*
X506299Y583977D01*
G01X528239Y589996D02*
X526845Y589699D01*
G01X642058Y612833D02*
X524084Y587757D01*
G01X532670Y590937D02*
X531276Y590641D01*
G01X642058Y612833D02*
X524084Y587757D01*
G01X748146Y636737D02*
X535629Y591566D01*
G01X642058Y612833D02*
X524084Y587757D01*
G01X506299Y583977D02*
X488514Y580197D01*
G01X523808Y589054D02*
X487998Y581442D01*
G01X524084Y587756D02*
X506299Y583977D01*
G01X523808Y589054D02*
X487998Y581442D01*
G01X642058Y612833D02*
X524084Y587757D01*
G01X528239Y589996D02*
X526845Y589699D01*
G01X532670Y590937D02*
X531276Y590641D01*
G01X748146Y636737D02*
X535629Y591566D01*
G01X748146Y636737D02*
X535629Y591566D01*
G01X559641Y941793D02*
X558247Y942090D01*
G01X564071Y940849D02*
X562678Y941146D01*
G01X749663Y901306D02*
X567108Y940202D01*
G01X559641Y941793D02*
X558247Y942090D01*
G01X564071Y940849D02*
X562678Y941146D01*
G01X749663Y901306D02*
X567108Y940202D01*
G01X484887Y937186D02*
X483486Y937447D01*
G01X729420Y891592D02*
X487861Y936631D01*
G01X484887Y937186D02*
X483486Y937447D01*
G01X729420Y891592D02*
X487861Y936631D01*
G01X504638Y979993D02*
X501100D01*
G01X504500Y978668D02*
X501100D01*
G01X641648Y951233D02*
X504638Y979993D01*
G01X652745Y947548D02*
X504500Y978668D01*
G01X652745Y947548D02*
X504500Y978668D01*
G01X652745Y947548D02*
X504500Y978668D01*
G01D02*
X501100D01*
G01X504638Y979993D02*
X501100D01*
G01X652745Y947548D02*
X504500Y978668D01*
G01X641648Y951233D02*
X504638Y979993D01*
G01X630138Y74481D02*
X625313D01*
G01X630643Y73156D02*
X625313D01*
G01X641161Y84308D02*
X630138Y74481D01*
G01X642316Y83561D02*
X630643Y73156D01*
G01X661187Y147933D02*
X641161Y84308D01*
G01X662471Y147595D02*
X642316Y83561D01*
G01X630643Y73156D02*
X625313D01*
G01X630138Y74481D02*
X625313D01*
G01X642316Y83561D02*
X630643Y73156D01*
G01X641161Y84308D02*
X630138Y74481D01*
G01X662471Y147595D02*
X642316Y83561D01*
G01X661187Y147933D02*
X641161Y84308D01*
G01X698739Y324605D02*
X661187Y147933D01*
G01X690761Y280693D02*
X662471Y147595D01*
G01X690761Y280693D02*
X662471Y147595D01*
G01X698739Y324605D02*
X661187Y147933D01*
G01X698739Y324605D02*
X661187Y147933D01*
G01X1002438Y634260D02*
X652801Y407203D01*
G01X1003396Y633302D02*
X653759Y406245D01*
G01X1003396Y633302D02*
X653759Y406245D01*
G01X1002438Y634260D02*
X652801Y407203D01*
G01X638000Y527237D02*
X625313D01*
G01X638266Y525912D02*
X625313D01*
G01X665755Y538832D02*
X638000Y527237D01*
G01X666377Y537655D02*
X638266Y525912D01*
G01X682358Y549614D02*
X665755Y538832D01*
G01X683316Y548656D02*
X666377Y537655D01*
G01X638266Y525912D02*
X625313D01*
G01X638000Y527237D02*
X625313D01*
G01X666377Y537655D02*
X638266Y525912D01*
G01X665755Y538832D02*
X638000Y527237D01*
G01X683316Y548656D02*
X666377Y537655D01*
G01X682358Y549614D02*
X665755Y538832D01*
G01X643063Y592172D02*
X612268Y585626D01*
G01X720202Y607214D02*
X612740Y584371D01*
G01X647495Y593115D02*
X646101Y592818D01*
G01X720202Y607214D02*
X612740Y584371D01*
G01X651926Y594056D02*
X650532Y593760D01*
G01X720202Y607214D02*
X612740Y584371D01*
G01X669183Y597724D02*
X654963Y594702D01*
G01X720202Y607214D02*
X612740Y584371D01*
G01X719686Y608459D02*
X669183Y597724D01*
G01X720202Y607214D02*
X612740Y584371D01*
G01X720202Y607214D02*
X612740Y584371D01*
G01X643063Y592172D02*
X612268Y585626D01*
G01X647495Y593115D02*
X646101Y592818D01*
G01X651926Y594056D02*
X650532Y593760D01*
G01X669183Y597724D02*
X654963Y594702D01*
G01X719686Y608459D02*
X669183Y597724D01*
G01X748662Y635492D02*
X642058Y612832D01*
G01X748662Y635492D02*
X642058Y612832D01*
G01X646082Y950302D02*
X644687Y950595D01*
G01X650515Y949372D02*
X649120Y949664D01*
G01X792713Y919522D02*
X653554Y948734D01*
G01X792716Y918167D02*
X652745Y947549D01*
G01X646082Y950302D02*
X644687Y950595D01*
G01X650515Y949372D02*
X649120Y949664D01*
G01X792716Y918167D02*
X652745Y947549D01*
G01X792713Y919522D02*
X653554Y948734D01*
G01X630697Y979993D02*
X625313D01*
G01X630570Y978668D02*
X625313D01*
G01X633121Y979524D02*
X630697Y979993D01*
G01X726907Y960016D02*
X630570Y978668D01*
G01X637490Y978679D02*
X636091Y978949D01*
G01X726907Y960016D02*
X630570Y978668D01*
G01X641859Y977833D02*
X640459Y978104D01*
G01X726907Y960016D02*
X630570Y978668D01*
G01X726750Y961405D02*
X644828Y977258D01*
G01X726907Y960016D02*
X630570Y978668D01*
G01D02*
X625313D01*
G01X630697Y979993D02*
X625313D01*
G01X726907Y960016D02*
X630570Y978668D01*
G01X633121Y979524D02*
X630697Y979993D01*
G01X637490Y978679D02*
X636091Y978949D01*
G01X641859Y977833D02*
X640459Y978104D01*
G01X726750Y961405D02*
X644828Y977258D01*
G01X753497Y74481D02*
X749526D01*
G01X753890Y73156D02*
X749526D01*
G01X757237Y76913D02*
X753497Y74481D01*
G01X757960Y75802D02*
X753890Y73156D01*
G01X758400Y76088D02*
X757960Y75802D01*
G01X757236Y76913D02*
X757237D01*
G01X757960Y75802D02*
X753890Y73156D01*
G01X758400Y76088D02*
X757960Y75802D01*
G01X758405Y81696D02*
X757236Y76913D01*
G01X760933Y86457D02*
X758400Y76088D01*
G01X759573Y86477D02*
X758405Y81696D01*
G01X760933Y86457D02*
X758400Y76088D01*
G01X748718Y137533D02*
X759573Y86477D01*
G01X750014Y137809D02*
X760933Y86457D01*
G01X753890Y73156D02*
X749526D01*
G01X753497Y74481D02*
X749526D01*
G01X757960Y75802D02*
X753890Y73156D01*
G01X757237Y76913D02*
X753497Y74481D01*
G01X757236Y76913D02*
X757237D01*
G01X758400Y76088D02*
X757960Y75802D01*
G01X757237Y76913D02*
X753497Y74481D01*
G01X757236Y76913D02*
X757237D01*
G01X760933Y86457D02*
X758400Y76088D01*
G01X758405Y81696D02*
X757236Y76913D01*
G01X759573Y86477D02*
X758405Y81696D01*
G01X750014Y137809D02*
X760933Y86457D01*
G01X748718Y137533D02*
X759573Y86477D01*
G01X739722Y179845D02*
X748718Y137533D01*
G01X741077Y179845D02*
X750014Y137809D01*
G01X747131Y214710D02*
X739722Y179845D01*
G01X798786Y451402D02*
X741077Y179845D01*
G01X798786Y451402D02*
X741077Y179845D01*
G01X798786Y451402D02*
X741077Y179845D01*
G01X798786Y451402D02*
X741077Y179845D01*
G01D02*
X750014Y137809D01*
G01X739722Y179845D02*
X748718Y137533D01*
G01X798786Y451402D02*
X741077Y179845D01*
G01X747131Y214710D02*
X739722Y179845D01*
G01X748056Y219063D02*
X747760Y217669D01*
G01X748981Y223416D02*
X748685Y222022D01*
G01X797541Y451918D02*
X749610Y226375D01*
G01X748056Y219063D02*
X747760Y217669D01*
G01X748981Y223416D02*
X748685Y222022D01*
G01X797541Y451918D02*
X749610Y226375D01*
G01X700036Y324331D02*
X690761Y280693D01*
G01X700036Y324331D02*
X690761Y280693D01*
G01X699681Y329036D02*
X699385Y327642D01*
G01X718155Y409575D02*
X700036Y324331D01*
G01X700623Y333467D02*
X700327Y332073D01*
G01X718155Y409575D02*
X700036Y324331D01*
G01X716910Y410091D02*
X701269Y336505D01*
G01X718155Y409575D02*
X700036Y324331D01*
G01X718155Y409575D02*
X700036Y324331D01*
G01X699681Y329036D02*
X699385Y327642D01*
G01X700623Y333467D02*
X700327Y332073D01*
G01X716910Y410091D02*
X701269Y336505D01*
G01X752008Y464137D02*
X716910Y410091D01*
G01X752966Y463179D02*
X718155Y409575D01*
G01X1005702Y628889D02*
X752008Y464137D01*
G01X1006660Y627931D02*
X752966Y463179D01*
G01D02*
X718155Y409575D01*
G01X752008Y464137D02*
X716910Y410091D01*
G01X1006660Y627931D02*
X752966Y463179D01*
G01X1005702Y628889D02*
X752008Y464137D01*
G01X756143Y527237D02*
X749526D01*
G01X756316Y525912D02*
X749526D01*
G01X782211Y534086D02*
X756143Y527237D01*
G01X817314Y541937D02*
X756316Y525912D01*
G01X817314Y541937D02*
X756316Y525912D01*
G01X817314Y541937D02*
X756316Y525912D01*
G01X817314Y541937D02*
X756316Y525912D01*
G01D02*
X749526D01*
G01X756143Y527237D02*
X749526D01*
G01X817314Y541937D02*
X756316Y525912D01*
G01X782211Y534086D02*
X756143Y527237D01*
G01X713297Y597229D02*
X682358Y549614D01*
G01X714255Y596271D02*
X683316Y548656D01*
G01X714255Y596271D02*
X683316Y548656D01*
G01X713297Y597229D02*
X682358Y549614D01*
G01X1029230Y802347D02*
X713297Y597229D01*
G01X1029817Y801148D02*
X714255Y596271D01*
G01X1029817Y801148D02*
X714255Y596271D01*
G01X1029230Y802347D02*
X713297Y597229D01*
G01X1047583Y821294D02*
X719686Y608459D01*
G01X1048099Y820049D02*
X720202Y607214D01*
G01X1048099Y820049D02*
X720202Y607214D01*
G01X1047583Y821294D02*
X719686Y608459D01*
G01X1048418Y831729D02*
X748146Y636737D01*
G01X1048934Y830484D02*
X748662Y635492D01*
G01X1048934Y830484D02*
X748662Y635492D01*
G01X1048418Y831729D02*
X748146Y636737D01*
G01X807424Y942902D02*
X726907Y960016D01*
G01X807424Y942902D02*
X726907Y960016D01*
G01X874365Y928064D02*
X749663Y901306D01*
G01X874366Y926709D02*
X749664Y899951D01*
G01X874366Y926709D02*
X749664Y899951D01*
G01X874365Y928064D02*
X749663Y901306D01*
G01X875611Y921370D02*
X729420Y891592D01*
G01X875605Y920016D02*
X729431Y890242D01*
G01X875605Y920016D02*
X729431Y890242D01*
G01X875611Y921370D02*
X729420Y891592D01*
G01X876452Y916512D02*
X679594Y874865D01*
G01X876451Y915157D02*
X679607Y873513D01*
G01X876451Y915157D02*
X679607Y873513D01*
G01X876452Y916512D02*
X679594Y874865D01*
G01X752183Y979993D02*
X749526D01*
G01X752028Y978668D02*
X749526D01*
G01X760990Y977917D02*
X752183Y979993D01*
G01X960799Y929456D02*
X752028Y978668D01*
G01X765322Y976896D02*
X763935Y977223D01*
G01X960799Y929456D02*
X752028Y978668D01*
G01X960799Y929456D02*
X752028Y978668D01*
G01X960799Y929456D02*
X752028Y978668D01*
G01D02*
X749526D01*
G01X752183Y979993D02*
X749526D01*
G01X960799Y929456D02*
X752028Y978668D01*
G01X760990Y977917D02*
X752183Y979993D01*
G01X765322Y976896D02*
X763935Y977223D01*
G01X807431Y944256D02*
X726750Y961405D01*
G01X807431Y944256D02*
X726750Y961405D01*
G01X802626Y459749D02*
X797541Y451918D01*
G01X803738Y459027D02*
X798786Y451402D01*
G01X813103Y475882D02*
X802626Y459749D01*
G01X814215Y475160D02*
X803738Y459027D01*
G01D02*
X798786Y451402D01*
G01X802626Y459749D02*
X797541Y451918D01*
G01X814215Y475160D02*
X803738Y459027D01*
G01X813103Y475882D02*
X802626Y459749D01*
G01X786592Y535237D02*
X785214Y534874D01*
G01X790974Y536388D02*
X789595Y536026D01*
G01X816771Y543165D02*
X793977Y537177D01*
G01X987673Y654153D02*
X816771Y543165D01*
G01X988631Y653195D02*
X817314Y541937D01*
G01X786592Y535237D02*
X785214Y534874D01*
G01X790974Y536388D02*
X789595Y536026D01*
G01X816771Y543165D02*
X793977Y537177D01*
G01X988631Y653195D02*
X817314Y541937D01*
G01X987673Y654153D02*
X816771Y543165D01*
G01X823579Y492013D02*
X813103Y475882D01*
G01X835166Y507423D02*
X814215Y475160D01*
G01X834208Y508381D02*
X823579Y492013D01*
G01X835166Y507423D02*
X814215Y475160D01*
G01X1011889Y623772D02*
X834208Y508381D01*
G01X1012847Y622814D02*
X835166Y507423D01*
G01D02*
X814215Y475160D01*
G01X823579Y492013D02*
X813103Y475882D01*
G01X834208Y508381D02*
X823579Y492013D01*
G01X1012847Y622814D02*
X835166Y507423D01*
G01X1011889Y623772D02*
X834208Y508381D01*
G01X1041784Y837137D02*
X775095Y663958D01*
G01X1042300Y835892D02*
X775611Y662713D01*
G01X1042300Y835892D02*
X775611Y662713D01*
G01X1041784Y837137D02*
X775095Y663958D01*
G01X1041511Y847056D02*
X796246Y687766D01*
G01X1042027Y845811D02*
X796762Y686521D01*
G01X1042027Y845811D02*
X796762Y686521D01*
G01X1041511Y847056D02*
X796246Y687766D01*
G01X842637Y951358D02*
X807431Y944256D01*
G01X842630Y950004D02*
X807424Y942902D01*
G01X961503Y926092D02*
X842637Y951358D01*
G01X961503Y924737D02*
X842630Y950004D01*
G01D02*
X807424Y942902D01*
G01X842637Y951358D02*
X807431Y944256D01*
G01X961503Y924737D02*
X842630Y950004D01*
G01X961503Y926092D02*
X842637Y951358D01*
G01X878962Y938040D02*
X792713Y919522D01*
G01X878963Y936685D02*
X792716Y918167D01*
G01X878963Y936685D02*
X792716Y918167D01*
G01X878962Y938040D02*
X792713Y919522D01*
G01X769653Y975875D02*
X768266Y976202D01*
G01X960814Y930814D02*
X772597Y975181D01*
G01X769653Y975875D02*
X768266Y976202D01*
G01X960814Y930814D02*
X772597Y975181D01*
G01X962914Y920196D02*
X878962Y938040D01*
G01X962914Y918841D02*
X878963Y936685D01*
G01X962914Y918841D02*
X878963Y936685D01*
G01X962914Y920196D02*
X878962Y938040D01*
G01X948784Y912244D02*
X874365Y928064D01*
G01X948784Y910889D02*
X874366Y926709D01*
G01X991233Y921268D02*
X948784Y912244D01*
G01X991233Y919913D02*
X948784Y910889D01*
G01D02*
X874366Y926709D01*
G01X948784Y912244D02*
X874365Y928064D01*
G01X991233Y919913D02*
X948784Y910889D01*
G01X991233Y921268D02*
X948784Y912244D01*
G01X948349Y905907D02*
X875611Y921370D01*
G01X948349Y904552D02*
X875605Y920016D01*
G01X992427Y915278D02*
X948349Y905907D01*
G01X992427Y913923D02*
X948349Y904552D01*
G01D02*
X875605Y920016D01*
G01X948349Y905907D02*
X875611Y921370D01*
G01X992427Y913923D02*
X948349Y904552D01*
G01X992427Y915278D02*
X948349Y905907D01*
G01X952053Y900443D02*
X876452Y916512D01*
G01X952053Y899088D02*
X876451Y915157D01*
G01X996047Y909794D02*
X952053Y900443D01*
G01X996028Y908435D02*
X952053Y899088D01*
G01D02*
X876451Y915157D01*
G01X952053Y900443D02*
X876452Y916512D01*
G01X996028Y908435D02*
X952053Y899088D01*
G01X996047Y909794D02*
X952053Y900443D01*
G01X1092320Y815294D02*
X987673Y654153D01*
G01X1093235Y814269D02*
X988631Y653195D01*
G01X1093235Y814269D02*
X988631Y653195D01*
G01X1092320Y815294D02*
X987673Y654153D01*
G01X1072895Y717709D02*
X1011889Y623772D01*
G01X1073853Y716751D02*
X1012847Y622814D01*
G01X1073853Y716751D02*
X1012847Y622814D01*
G01X1072895Y717709D02*
X1011889Y623772D01*
G01X1067290Y723727D02*
X1005702Y628889D01*
G01X1068248Y722769D02*
X1006660Y627931D01*
G01X1068248Y722769D02*
X1006660Y627931D01*
G01X1067290Y723727D02*
X1005702Y628889D01*
G01X1065547Y731437D02*
X1002438Y634260D01*
G01X1066505Y730479D02*
X1003396Y633302D01*
G01X1066505Y730479D02*
X1003396Y633302D01*
G01X1065547Y731437D02*
X1002438Y634260D01*
G01X1031027Y689237D02*
X999448Y640609D01*
G01X1063873Y737382D02*
X1000406Y639651D01*
G01X1063873Y737382D02*
X1000406Y639651D01*
G01X1063873Y737382D02*
X1000406Y639651D01*
G01X1031027Y689237D02*
X999448Y640609D01*
G01X1059377Y742694D02*
X996226Y645448D01*
G01X1060335Y741736D02*
X997184Y644490D01*
G01X1060335Y741736D02*
X997184Y644490D01*
G01X1059377Y742694D02*
X996226Y645448D01*
G01X1059890Y751404D02*
X995361Y652014D01*
G01X1060848Y750446D02*
X996319Y651056D01*
G01X1060848Y750446D02*
X996319Y651056D01*
G01X1059890Y751404D02*
X995361Y652014D01*
G01X1062915Y738340D02*
X1031027Y689237D01*
G01X1062915Y738340D02*
X1031027Y689237D01*
G01X1053840Y810912D02*
X1029230Y802347D01*
G01X1090165Y822150D02*
X1029817Y801148D01*
G01X1090165Y822150D02*
X1029817Y801148D01*
G01X1090165Y822150D02*
X1029817Y801148D01*
G01X1090165Y822150D02*
X1029817Y801148D01*
G01X1090165Y822150D02*
X1029817Y801148D01*
G01X1053840Y810912D02*
X1029230Y802347D01*
G01X1091177Y830562D02*
X1047583Y821294D01*
G01X1091317Y829237D02*
X1048099Y820049D01*
G01X1091317Y829237D02*
X1048099Y820049D01*
G01X1091177Y830562D02*
X1047583Y821294D01*
G01X1076261Y837648D02*
X1048418Y831729D01*
G01X1076401Y836323D02*
X1048934Y830484D01*
G01X1076401Y836323D02*
X1048934Y830484D01*
G01X1076261Y837648D02*
X1048418Y831729D01*
G01X1077495Y844735D02*
X1041784Y837137D01*
G01X1077635Y843410D02*
X1042300Y835892D01*
G01X1077635Y843410D02*
X1042300Y835892D01*
G01X1077495Y844735D02*
X1041784Y837137D01*
G01X1063933Y851822D02*
X1041511Y847056D01*
G01X1064073Y850497D02*
X1042027Y845811D01*
G01X1064073Y850497D02*
X1042027Y845811D01*
G01X1063933Y851822D02*
X1041511Y847056D01*
G01X989264Y936861D02*
X960814Y930814D01*
G01X975315Y932541D02*
X960799Y929456D01*
G01X989404Y935536D02*
X975315Y932541D01*
G01X1128457Y936861D02*
X989264D01*
G01X1128457Y935536D02*
X989404D01*
G01X975315Y932541D02*
X960799Y929456D01*
G01X989264Y936861D02*
X960814Y930814D01*
G01X989404Y935536D02*
X975315Y932541D01*
G01X989264Y936861D02*
X960814Y930814D01*
G01X1128457Y935536D02*
X989404D01*
G01X1128457Y936861D02*
X989264D01*
G01X991610Y932490D02*
X961503Y926092D01*
G01X991610Y931135D02*
X961503Y924737D01*
G01X1004384Y929774D02*
X991610Y932490D01*
G01X1004244Y928449D02*
X991610Y931135D01*
G01X1124520Y929774D02*
X1004384D01*
G01X1124520Y928449D02*
X1004244D01*
G01X991610Y931135D02*
X961503Y924737D01*
G01X991610Y932490D02*
X961503Y926092D01*
G01X1004244Y928449D02*
X991610Y931135D01*
G01X1004384Y929774D02*
X991610Y932490D01*
G01X1124520Y928449D02*
X1004244D01*
G01X1124520Y929774D02*
X1004384D01*
G01X992335Y926451D02*
X962914Y920196D01*
G01X992335Y925096D02*
X962914Y918841D01*
G01X1010035Y922688D02*
X992335Y926451D01*
G01X1009895Y921363D02*
X992335Y925096D01*
G01X1128457Y922688D02*
X1010035D01*
G01X1128457Y921363D02*
X1009895D01*
G01X992335Y925096D02*
X962914Y918841D01*
G01X992335Y926451D02*
X962914Y920196D01*
G01X1009895Y921363D02*
X992335Y925096D01*
G01X1010035Y922688D02*
X992335Y926451D01*
G01X1128457Y921363D02*
X1009895D01*
G01X1128457Y922688D02*
X1010035D01*
G01X1017898Y915601D02*
X991233Y921268D01*
G01X1017758Y914276D02*
X991233Y919913D01*
G01X1124520Y915601D02*
X1017898D01*
G01X1124520Y914276D02*
X1017758D01*
G01D02*
X991233Y919913D01*
G01X1017898Y915601D02*
X991233Y921268D01*
G01X1124520Y914276D02*
X1017758D01*
G01X1124520Y915601D02*
X1017898D01*
G01X1024244Y908515D02*
X992427Y915278D01*
G01X1024104Y907190D02*
X992427Y913923D01*
G01X1128457Y908515D02*
X1024244D01*
G01X1128457Y907190D02*
X1024104D01*
G01D02*
X992427Y913923D01*
G01X1024244Y908515D02*
X992427Y915278D01*
G01X1128457Y907190D02*
X1024104D01*
G01X1128457Y908515D02*
X1024244D01*
G01X1030559Y901428D02*
X996047Y909794D01*
G01X1030400Y900103D02*
X996028Y908435D01*
G01X1124520Y901428D02*
X1030559D01*
G01X1124520Y900103D02*
X1030400D01*
G01D02*
X996028Y908435D01*
G01X1030559Y901428D02*
X996047Y909794D01*
G01X1124520Y900103D02*
X1030400D01*
G01X1124520Y901428D02*
X1030559D01*
G01X1142082Y722938D02*
X1199718Y685507D01*
G01X1142475Y724263D02*
X1200676Y686465D01*
G01X1132058Y722938D02*
X1142082D01*
G01X1132058Y724263D02*
X1142475D01*
G01X1129796Y725200D02*
G03X1132058Y722938I2262J0D01*
G01X1131121Y725200D02*
G03X1132058Y724263I937J0D01*
G01X1129796Y726400D02*
Y725200D01*
G01X1131121Y726400D02*
Y725200D01*
G01X1142475Y724263D02*
X1200676Y686465D01*
G01X1142082Y722938D02*
X1199718Y685507D01*
G01X1132058Y724263D02*
X1142475D01*
G01X1132058Y722938D02*
X1142082D01*
G01X1131121Y725200D02*
G03X1132058Y724263I937J0D01*
G01X1129796Y725200D02*
G03X1132058Y722938I2262J0D01*
G01X1131121Y726400D02*
Y725200D01*
G01X1129796Y726400D02*
Y725200D01*
G01X1141728Y715851D02*
X1195616Y680859D01*
G01X1142121Y717176D02*
X1196574Y681817D01*
G01X1128121Y715851D02*
X1141728D01*
G01X1128121Y717176D02*
X1142121D01*
G01X1125859Y718113D02*
G03X1128121Y715851I2262J0D01*
G01X1127184Y718113D02*
G03X1128121Y717176I937J0D01*
G01X1125859Y719313D02*
Y718113D01*
G01X1127184Y719313D02*
Y718113D01*
G01X1142121Y717176D02*
X1196574Y681817D01*
G01X1141728Y715851D02*
X1195616Y680859D01*
G01X1128121Y717176D02*
X1142121D01*
G01X1128121Y715851D02*
X1141728D01*
G01X1127184Y718113D02*
G03X1128121Y717176I937J0D01*
G01X1125859Y718113D02*
G03X1128121Y715851I2262J0D01*
G01X1127184Y719313D02*
Y718113D01*
G01X1125859Y719313D02*
Y718113D01*
G01X1142502Y710089D02*
X1189483Y679581D01*
G01X1142109Y708764D02*
X1188525Y678623D01*
G01X1142502Y710089D02*
X1189483Y679581D01*
G01X1132058Y708764D02*
X1142109D01*
G01X1132058Y710089D02*
X1142502D01*
G01X1129796Y711026D02*
G03X1132058Y708764I2262J0D01*
G01X1131121Y711026D02*
G03X1132058Y710089I937J0D01*
G01X1129796Y712226D02*
Y711026D01*
G01X1131121Y712226D02*
Y711026D01*
G01X1142502Y710089D02*
X1189483Y679581D01*
G01X1142109Y708764D02*
X1188525Y678623D01*
G01X1132058Y710089D02*
X1142502D01*
G01X1132058Y708764D02*
X1142109D01*
G01X1131121Y711026D02*
G03X1132058Y710089I937J0D01*
G01X1129796Y711026D02*
G03X1132058Y708764I2262J0D01*
G01X1131121Y712226D02*
Y711026D01*
G01X1129796Y712226D02*
Y711026D01*
G01X1141359Y701678D02*
X1184215Y673850D01*
G01X1141752Y703003D02*
X1185173Y674808D01*
G01X1128121Y701678D02*
X1141359D01*
G01X1128121Y703003D02*
X1141752D01*
G01X1125859Y703940D02*
G03X1128121Y701678I2262J0D01*
G01X1127184Y703940D02*
G03X1128121Y703003I937J0D01*
G01X1125859Y705140D02*
Y703940D01*
G01X1127184Y705140D02*
Y703940D01*
G01X1141752Y703003D02*
X1185173Y674808D01*
G01X1141359Y701678D02*
X1184215Y673850D01*
G01X1128121Y703003D02*
X1141752D01*
G01X1128121Y701678D02*
X1141359D01*
G01X1127184Y703940D02*
G03X1128121Y703003I937J0D01*
G01X1125859Y703940D02*
G03X1128121Y701678I2262J0D01*
G01X1127184Y705140D02*
Y703940D01*
G01X1125859Y705140D02*
Y703940D01*
G01X1135259Y694591D02*
X1169876Y672108D01*
G01X1135652Y695916D02*
X1170834Y673066D01*
G01X1132058Y694591D02*
X1135259D01*
G01X1132058Y695916D02*
X1135652D01*
G01X1129796Y696853D02*
G03X1132058Y694591I2262J0D01*
G01X1131121Y696853D02*
G03X1132058Y695916I937J0D01*
G01X1129796Y698053D02*
Y696853D01*
G01X1131121Y698053D02*
Y696853D01*
G01X1135652Y695916D02*
X1170834Y673066D01*
G01X1135259Y694591D02*
X1169876Y672108D01*
G01X1132058Y695916D02*
X1135652D01*
G01X1132058Y694591D02*
X1135259D01*
G01X1131121Y696853D02*
G03X1132058Y695916I937J0D01*
G01X1129796Y696853D02*
G03X1132058Y694591I2262J0D01*
G01X1131121Y698053D02*
Y696853D01*
G01X1129796Y698053D02*
Y696853D01*
G01X1147567Y680234D02*
X1161204Y671380D01*
G01X1148163Y681427D02*
X1162162Y672338D01*
G01X1127171Y687686D02*
X1147567Y680234D01*
G01X1127901Y688830D02*
X1148163Y681427D01*
G01X1126528Y688329D02*
X1127171Y687686D01*
G01X1127516Y689215D02*
X1127901Y688830D01*
G01X1127340Y689392D02*
X1127516Y689215D01*
G01X1125859Y689766D02*
G03X1126402Y688456I1856J2D01*
G01X1127184Y689767D02*
G03X1127340Y689392I531J1D01*
G01X1125859Y690967D02*
Y689766D01*
G01X1127184Y690967D02*
Y689767D01*
G01X1148163Y681427D02*
X1162162Y672338D01*
G01X1147567Y680234D02*
X1161204Y671380D01*
G01X1127901Y688830D02*
X1148163Y681427D01*
G01X1127171Y687686D02*
X1147567Y680234D01*
G01X1127516Y689215D02*
X1127901Y688830D01*
G01X1126528Y688329D02*
X1127171Y687686D01*
G01X1127340Y689392D02*
X1127516Y689215D01*
G01X1126528Y688329D02*
X1127171Y687686D01*
G01X1127184Y689767D02*
G03X1127340Y689392I531J1D01*
G01X1125859Y689766D02*
G03X1126402Y688456I1856J2D01*
G01X1127184Y690967D02*
Y689767D01*
G01X1125859Y690967D02*
Y689766D01*
G01X1093901Y731349D02*
X1072895Y717709D01*
G01X1094294Y730024D02*
X1073853Y716751D01*
G01X1124520Y731349D02*
X1093901D01*
G01X1124520Y730024D02*
X1094294D01*
G01X1125859Y732688D02*
G02X1124520Y731349I-1339J0D01*
G01X1127184Y732688D02*
G02X1124520Y730024I-2664J0D01*
G01X1125859Y733588D02*
Y732688D01*
G01X1127184Y733588D02*
Y732688D01*
G01X1094294Y730024D02*
X1073853Y716751D01*
G01X1093901Y731349D02*
X1072895Y717709D01*
G01X1124520Y730024D02*
X1094294D01*
G01X1124520Y731349D02*
X1093901D01*
G01X1127184Y732688D02*
G02X1124520Y730024I-2664J0D01*
G01X1125859Y732688D02*
G02X1124520Y731349I-1339J0D01*
G01X1127184Y733588D02*
Y732688D01*
G01X1125859Y733588D02*
Y732688D01*
G01X1089942Y738436D02*
X1067290Y723727D01*
G01X1090335Y737111D02*
X1068248Y722769D01*
G01X1128457Y738436D02*
X1089942D01*
G01X1128457Y737111D02*
X1090335D01*
G01X1129796Y739775D02*
G02X1128457Y738436I-1339J0D01*
G01X1131121Y739775D02*
G02X1128457Y737111I-2664J0D01*
G01X1129796Y740675D02*
Y739775D01*
G01X1131121Y740675D02*
Y739775D01*
G01X1090335Y737111D02*
X1068248Y722769D01*
G01X1089942Y738436D02*
X1067290Y723727D01*
G01X1128457Y737111D02*
X1090335D01*
G01X1128457Y738436D02*
X1089942D01*
G01X1131121Y739775D02*
G02X1128457Y737111I-2664J0D01*
G01X1129796Y739775D02*
G02X1128457Y738436I-1339J0D01*
G01X1131121Y740675D02*
Y739775D01*
G01X1129796Y740675D02*
Y739775D01*
G01X1087235Y745522D02*
X1065547Y731437D01*
G01X1087628Y744197D02*
X1066505Y730479D01*
G01X1124520Y745522D02*
X1087235D01*
G01X1124520Y744197D02*
X1087628D01*
G01X1125859Y746861D02*
G02X1124520Y745522I-1339J0D01*
G01X1127184Y746861D02*
G02X1124520Y744197I-2664J0D01*
G01X1125859Y747761D02*
Y746861D01*
G01X1127184Y747761D02*
Y746861D01*
G01X1087628Y744197D02*
X1066505Y730479D01*
G01X1087235Y745522D02*
X1065547Y731437D01*
G01X1124520Y744197D02*
X1087628D01*
G01X1124520Y745522D02*
X1087235D01*
G01X1127184Y746861D02*
G02X1124520Y744197I-2664J0D01*
G01X1125859Y746861D02*
G02X1124520Y745522I-1339J0D01*
G01X1127184Y747761D02*
Y746861D01*
G01X1125859Y747761D02*
Y746861D01*
G01X1084883Y752609D02*
X1062915Y738340D01*
G01X1085276Y751284D02*
X1063873Y737382D01*
G01X1128457Y752609D02*
X1084883D01*
G01X1128457Y751284D02*
X1085276D01*
G01X1129796Y753948D02*
G02X1128457Y752609I-1339J0D01*
G01X1131121Y753948D02*
G02X1128457Y751284I-2664J0D01*
G01X1129796Y754848D02*
Y753948D01*
G01X1131121Y754848D02*
Y753948D01*
G01X1085276Y751284D02*
X1063873Y737382D01*
G01X1084883Y752609D02*
X1062915Y738340D01*
G01X1128457Y751284D02*
X1085276D01*
G01X1128457Y752609D02*
X1084883D01*
G01X1131121Y753948D02*
G02X1128457Y751284I-2664J0D01*
G01X1129796Y753948D02*
G02X1128457Y752609I-1339J0D01*
G01X1131121Y754848D02*
Y753948D01*
G01X1129796Y754848D02*
Y753948D01*
G01X1084427Y758960D02*
X1059377Y742694D01*
G01X1084943Y757715D02*
X1060335Y741736D01*
G01X1087889Y759696D02*
X1084427Y758960D01*
G01X1088029Y758371D02*
X1084943Y757715D01*
G01X1124520Y759696D02*
X1087889D01*
G01X1124520Y758371D02*
X1088029D01*
G01X1125859Y761035D02*
G02X1124520Y759696I-1339J0D01*
G01X1127184Y761035D02*
G02X1124520Y758371I-2664J0D01*
G01X1125859Y761935D02*
Y761035D01*
G01X1127184Y761935D02*
Y761035D01*
G01X1084943Y757715D02*
X1060335Y741736D01*
G01X1084427Y758960D02*
X1059377Y742694D01*
G01X1088029Y758371D02*
X1084943Y757715D01*
G01X1087889Y759696D02*
X1084427Y758960D01*
G01X1124520Y758371D02*
X1088029D01*
G01X1124520Y759696D02*
X1087889D01*
G01X1127184Y761035D02*
G02X1124520Y758371I-2664J0D01*
G01X1125859Y761035D02*
G02X1124520Y759696I-1339J0D01*
G01X1127184Y761935D02*
Y761035D01*
G01X1125859Y761935D02*
Y761035D01*
G01X1081358Y765351D02*
X1059890Y751404D01*
G01X1081874Y764106D02*
X1060848Y750446D01*
G01X1081874Y764106D02*
X1060848Y750446D01*
G01X1081358Y765351D02*
X1059890Y751404D01*
G01X1132119Y807977D02*
X1178409D01*
G01X1132119Y809302D02*
X1178498D01*
G01X1129796Y810300D02*
G03X1132119Y807977I2323J0D01*
G01X1131121Y810300D02*
G03X1132119Y809302I998J0D01*
G01X1129796Y811300D02*
Y810300D01*
G01X1131121Y811300D02*
Y810300D01*
G01X1132119Y809302D02*
X1178498D01*
G01X1132119Y807977D02*
X1178409D01*
G01X1131121Y810300D02*
G03X1132119Y809302I998J0D01*
G01X1129796Y810300D02*
G03X1132119Y807977I2323J0D01*
G01X1131121Y811300D02*
Y810300D01*
G01X1129796Y811300D02*
Y810300D01*
G01X1128182Y800890D02*
X1177189D01*
G01X1128182Y802215D02*
X1177269D01*
G01X1125859Y803213D02*
G03X1128182Y800890I2323J0D01*
G01X1127184Y803213D02*
G03X1128182Y802215I998J0D01*
G01X1125859Y804213D02*
Y803213D01*
G01X1127184Y804213D02*
Y803213D01*
G01X1128182Y802215D02*
X1177269D01*
G01X1128182Y800890D02*
X1177189D01*
G01X1127184Y803213D02*
G03X1128182Y802215I998J0D01*
G01X1125859Y803213D02*
G03X1128182Y800890I2323J0D01*
G01X1127184Y804213D02*
Y803213D01*
G01X1125859Y804213D02*
Y803213D01*
G01X1135382Y793804D02*
X1324514Y763151D01*
G01X1135489Y795129D02*
X1325002Y764415D01*
G01X1132119Y793804D02*
X1135382D01*
G01X1132119Y795129D02*
X1135489D01*
G01X1129796Y796127D02*
G03X1132119Y793804I2323J0D01*
G01X1131121Y796127D02*
G03X1132119Y795129I998J0D01*
G01X1129796Y797127D02*
Y796127D01*
G01X1131121Y797127D02*
Y796127D01*
G01X1135489Y795129D02*
X1325002Y764415D01*
G01X1135382Y793804D02*
X1324514Y763151D01*
G01X1132119Y795129D02*
X1135489D01*
G01X1132119Y793804D02*
X1135382D01*
G01X1131121Y796127D02*
G03X1132119Y795129I998J0D01*
G01X1129796Y796127D02*
G03X1132119Y793804I2323J0D01*
G01X1131121Y797127D02*
Y796127D01*
G01X1129796Y797127D02*
Y796127D01*
G01X1146504Y786717D02*
X1315250Y758684D01*
G01X1146614Y788042D02*
X1315740Y759946D01*
G01X1128182Y786717D02*
X1146504D01*
G01X1128182Y788042D02*
X1146614D01*
G01X1125859Y789040D02*
G03X1128182Y786717I2323J0D01*
G01X1127184Y789040D02*
G03X1128182Y788042I998J0D01*
G01X1125859Y790040D02*
Y789040D01*
G01X1127184Y790040D02*
Y789040D01*
G01X1146614Y788042D02*
X1315740Y759946D01*
G01X1146504Y786717D02*
X1315250Y758684D01*
G01X1128182Y788042D02*
X1146614D01*
G01X1128182Y786717D02*
X1146504D01*
G01X1127184Y789040D02*
G03X1128182Y788042I998J0D01*
G01X1125859Y789040D02*
G03X1128182Y786717I2323J0D01*
G01X1127184Y790040D02*
Y789040D01*
G01X1125859Y790040D02*
Y789040D01*
G01X1139599Y779630D02*
X1227390Y748266D01*
G01X1139829Y780955D02*
X1228012Y749451D01*
G01X1132119Y779630D02*
X1139599D01*
G01X1132119Y780955D02*
X1139829D01*
G01X1129796Y781953D02*
G03X1132119Y779630I2323J0D01*
G01X1131121Y781953D02*
G03X1132119Y780955I998J0D01*
G01X1129796Y782953D02*
Y781953D01*
G01X1131121Y782953D02*
Y781953D01*
G01X1139829Y780955D02*
X1228012Y749451D01*
G01X1139599Y779630D02*
X1227390Y748266D01*
G01X1132119Y780955D02*
X1139829D01*
G01X1132119Y779630D02*
X1139599D01*
G01X1131121Y781953D02*
G03X1132119Y780955I998J0D01*
G01X1129796Y781953D02*
G03X1132119Y779630I2323J0D01*
G01X1131121Y782953D02*
Y781953D01*
G01X1129796Y782953D02*
Y781953D01*
G01X1141289Y772544D02*
X1162391Y761626D01*
G01X1141612Y773869D02*
X1163325Y762636D01*
G01X1128182Y772544D02*
X1141289D01*
G01X1128182Y773869D02*
X1141612D01*
G01X1125859Y774867D02*
G03X1128182Y772544I2323J0D01*
G01X1127184Y774867D02*
G03X1128182Y773869I998J0D01*
G01X1125859Y775867D02*
Y774867D01*
G01X1127184Y775867D02*
Y774867D01*
G01X1141612Y773869D02*
X1163325Y762636D01*
G01X1141289Y772544D02*
X1162391Y761626D01*
G01X1128182Y773869D02*
X1141612D01*
G01X1128182Y772544D02*
X1141289D01*
G01X1127184Y774867D02*
G03X1128182Y773869I998J0D01*
G01X1125859Y774867D02*
G03X1128182Y772544I2323J0D01*
G01X1127184Y775867D02*
Y774867D01*
G01X1125859Y775867D02*
Y774867D01*
G01X1094514Y816389D02*
X1092320Y815294D01*
G01X1094827Y815064D02*
X1093235Y814269D01*
G01X1124520Y816389D02*
X1094514D01*
G01X1124520Y815064D02*
X1094827D01*
G01X1125859Y817728D02*
G02X1124520Y816389I-1339J0D01*
G01X1127184Y817728D02*
G02X1124520Y815064I-2664J0D01*
G01X1125859Y818628D02*
Y817728D01*
G01X1127184Y818628D02*
Y817728D01*
G01X1094827Y815064D02*
X1093235Y814269D01*
G01X1094514Y816389D02*
X1092320Y815294D01*
G01X1124520Y815064D02*
X1094827D01*
G01X1124520Y816389D02*
X1094514D01*
G01X1127184Y817728D02*
G02X1124520Y815064I-2664J0D01*
G01X1125859Y817728D02*
G02X1124520Y816389I-1339J0D01*
G01X1127184Y818628D02*
Y817728D01*
G01X1125859Y818628D02*
Y817728D01*
G01X1058118Y812401D02*
X1056772Y811932D01*
G01X1062396Y813889D02*
X1061050Y813421D01*
G01X1089941Y823475D02*
X1065329Y814910D01*
G01X1128457Y823475D02*
X1089941D01*
G01X1128457Y822150D02*
X1090165D01*
G01X1129796Y824814D02*
G02X1128457Y823475I-1339J0D01*
G01X1131121Y824814D02*
G02X1128457Y822150I-2664J0D01*
G01X1129796Y825714D02*
Y824814D01*
G01X1131121Y825714D02*
Y824814D01*
G01X1058118Y812401D02*
X1056772Y811932D01*
G01X1062396Y813889D02*
X1061050Y813421D01*
G01X1089941Y823475D02*
X1065329Y814910D01*
G01X1128457Y822150D02*
X1090165D01*
G01X1128457Y823475D02*
X1089941D01*
G01X1131121Y824814D02*
G02X1128457Y822150I-2664J0D01*
G01X1129796Y824814D02*
G02X1128457Y823475I-1339J0D01*
G01X1131121Y825714D02*
Y824814D01*
G01X1129796Y825714D02*
Y824814D01*
G01X1124520Y830562D02*
X1091177D01*
G01X1124520Y829237D02*
X1091317D01*
G01X1125859Y831901D02*
G02X1124520Y830562I-1339J0D01*
G01X1127184Y831901D02*
G02X1124520Y829237I-2664J0D01*
G01X1125859Y832801D02*
Y831901D01*
G01X1127184Y832801D02*
Y831901D01*
G01X1124520Y829237D02*
X1091317D01*
G01X1124520Y830562D02*
X1091177D01*
G01X1127184Y831901D02*
G02X1124520Y829237I-2664J0D01*
G01X1125859Y831901D02*
G02X1124520Y830562I-1339J0D01*
G01X1127184Y832801D02*
Y831901D01*
G01X1125859Y832801D02*
Y831901D01*
G01X1128457Y837648D02*
X1076261D01*
G01X1128457Y836323D02*
X1076401D01*
G01X1129796Y838987D02*
G02X1128457Y837648I-1339J0D01*
G01X1131121Y838987D02*
G02X1128457Y836323I-2664J0D01*
G01X1129796Y839887D02*
Y838987D01*
G01X1131121Y839887D02*
Y838987D01*
G01X1128457Y836323D02*
X1076401D01*
G01X1128457Y837648D02*
X1076261D01*
G01X1131121Y838987D02*
G02X1128457Y836323I-2664J0D01*
G01X1129796Y838987D02*
G02X1128457Y837648I-1339J0D01*
G01X1131121Y839887D02*
Y838987D01*
G01X1129796Y839887D02*
Y838987D01*
G01X1124520Y844735D02*
X1077495D01*
G01X1124520Y843410D02*
X1077635D01*
G01X1125859Y846074D02*
G02X1124520Y844735I-1339J0D01*
G01X1127184Y846074D02*
G02X1124520Y843410I-2664J0D01*
G01X1125859Y846974D02*
Y846074D01*
G01X1127184Y846974D02*
Y846074D01*
G01X1124520Y843410D02*
X1077635D01*
G01X1124520Y844735D02*
X1077495D01*
G01X1127184Y846074D02*
G02X1124520Y843410I-2664J0D01*
G01X1125859Y846074D02*
G02X1124520Y844735I-1339J0D01*
G01X1127184Y846974D02*
Y846074D01*
G01X1125859Y846974D02*
Y846074D01*
G01X1128457Y851822D02*
X1063933D01*
G01X1128457Y850497D02*
X1064073D01*
G01X1129796Y853161D02*
G02X1128457Y851822I-1339J0D01*
G01X1131121Y853161D02*
G02X1128457Y850497I-2664J0D01*
G01X1129796Y854061D02*
Y853161D01*
G01X1131121Y854061D02*
Y853161D01*
G01X1128457Y850497D02*
X1064073D01*
G01X1128457Y851822D02*
X1063933D01*
G01X1131121Y853161D02*
G02X1128457Y850497I-2664J0D01*
G01X1129796Y853161D02*
G02X1128457Y851822I-1339J0D01*
G01X1131121Y854061D02*
Y853161D01*
G01X1129796Y854061D02*
Y853161D01*
G01X1088090Y766782D02*
X1081358Y765351D01*
G01X1088230Y765457D02*
X1081874Y764106D01*
G01X1128457Y766782D02*
X1088090D01*
G01X1128457Y765457D02*
X1088230D01*
G01X1129796Y768121D02*
G02X1128457Y766782I-1339J0D01*
G01X1131121Y768121D02*
G02X1128457Y765457I-2664J0D01*
G01X1129796Y769021D02*
Y768121D01*
G01X1131121Y769021D02*
Y768121D01*
G01X1088230Y765457D02*
X1081874Y764106D01*
G01X1088090Y766782D02*
X1081358Y765351D01*
G01X1128457Y765457D02*
X1088230D01*
G01X1128457Y766782D02*
X1088090D01*
G01X1131121Y768121D02*
G02X1128457Y765457I-2664J0D01*
G01X1129796Y768121D02*
G02X1128457Y766782I-1339J0D01*
G01X1131121Y769021D02*
Y768121D01*
G01X1129796Y769021D02*
Y768121D01*
G01X1146721Y878843D02*
X1508928Y926876D01*
G01X1146633Y880168D02*
X1327616Y904169D01*
G01X1146721Y878843D02*
X1508928Y926876D01*
G01X1128327Y880168D02*
X1146633D01*
G01X1128327Y878843D02*
X1146721D01*
G01X1125859Y877700D02*
G02X1128327Y880168I2468J0D01*
G01X1127184Y877700D02*
G02X1128327Y878843I1143J0D01*
G01X1125859Y876700D02*
Y877700D01*
G01X1127184Y876700D02*
Y877700D01*
G01X1146721Y878843D02*
X1508928Y926876D01*
G01X1146633Y880168D02*
X1327616Y904169D01*
G01X1128327Y878843D02*
X1146721D01*
G01X1128327Y880168D02*
X1146633D01*
G01X1127184Y877700D02*
G02X1128327Y878843I1143J0D01*
G01X1125859Y877700D02*
G02X1128327Y880168I2468J0D01*
G01X1127184Y876700D02*
Y877700D01*
G01X1125859Y876700D02*
Y877700D01*
G01X1147932Y887255D02*
X1394480Y933784D01*
G01X1148056Y885930D02*
X1356090Y925190D01*
G01X1132400Y887255D02*
X1147932D01*
G01X1132400Y885930D02*
X1148056D01*
G01X1129796Y884651D02*
G02X1132400Y887255I2604J0D01*
G01X1131121Y884651D02*
G02X1132400Y885930I1279J0D01*
G01X1129796Y883799D02*
Y884651D01*
G01X1131121Y883800D02*
Y884651D01*
G01X1147932Y887255D02*
X1394480Y933784D01*
G01X1147932Y887255D02*
X1394480Y933784D01*
G01X1148056Y885930D02*
X1356090Y925190D01*
G01X1147932Y887255D02*
X1394480Y933784D01*
G01X1132400Y885930D02*
X1148056D01*
G01X1132400Y887255D02*
X1147932D01*
G01X1131121Y884651D02*
G02X1132400Y885930I1279J0D01*
G01X1129796Y884651D02*
G02X1132400Y887255I2604J0D01*
G01X1131121Y883800D02*
Y884651D01*
G01X1129796Y883799D02*
Y884651D01*
G01X1143867Y894342D02*
X1259102Y924080D01*
G01X1144036Y893017D02*
X1201816Y907928D01*
G01X1128301Y894342D02*
X1143867D01*
G01X1128301Y893017D02*
X1144036D01*
G01X1125859Y891900D02*
G02X1128301Y894342I2442J0D01*
G01X1127184Y891900D02*
G02X1128301Y893017I1117J0D01*
G01X1125859Y891100D02*
Y891900D01*
G01X1127184Y891100D02*
Y891900D01*
G01X1143867Y894342D02*
X1259102Y924080D01*
G01X1144036Y893017D02*
X1201816Y907928D01*
G01X1143867Y894342D02*
X1259102Y924080D01*
G01X1128301Y893017D02*
X1144036D01*
G01X1128301Y894342D02*
X1143867D01*
G01X1127184Y891900D02*
G02X1128301Y893017I1117J0D01*
G01X1125859Y891900D02*
G02X1128301Y894342I2442J0D01*
G01X1127184Y891100D02*
Y891900D01*
G01X1125859Y891100D02*
Y891900D01*
G01X1145452Y901428D02*
X1266433Y979993D01*
G01X1145845Y900103D02*
X1224403Y951118D01*
G01X1132324Y901428D02*
X1145452D01*
G01X1132324Y900103D02*
X1145845D01*
G01X1129796Y898900D02*
G02X1132324Y901428I2528J0D01*
G01X1131121Y898900D02*
G02X1132324Y900103I1203J0D01*
G01X1129796Y898000D02*
Y898900D01*
G01X1131121Y898000D02*
Y898900D01*
G01X1145452Y901428D02*
X1266433Y979993D01*
G01X1145452Y901428D02*
X1266433Y979993D01*
G01X1145452Y901428D02*
X1266433Y979993D01*
G01X1145845Y900103D02*
X1224403Y951118D01*
G01X1145452Y901428D02*
X1266433Y979993D01*
G01X1132324Y900103D02*
X1145845D01*
G01X1132324Y901428D02*
X1145452D01*
G01X1131121Y898900D02*
G02X1132324Y900103I1203J0D01*
G01X1129796Y898900D02*
G02X1132324Y901428I2528J0D01*
G01X1131121Y898000D02*
Y898900D01*
G01X1129796Y898000D02*
Y898900D01*
G01X1128254Y865995D02*
X1149081D01*
G01X1128254Y864670D02*
X1149140D01*
G01X1125859Y863600D02*
G02X1128254Y865995I2395J0D01*
G01X1127184Y863600D02*
G02X1128254Y864670I1070J0D01*
G01X1125859Y862600D02*
Y863600D01*
G01X1127184Y862600D02*
Y863600D01*
G01X1128254Y864670D02*
X1149140D01*
G01X1128254Y865995D02*
X1149081D01*
G01X1127184Y863600D02*
G02X1128254Y864670I1070J0D01*
G01X1125859Y863600D02*
G02X1128254Y865995I2395J0D01*
G01X1127184Y862600D02*
Y863600D01*
G01X1125859Y862600D02*
Y863600D01*
G01X1146212Y873082D02*
X1595889Y915690D01*
G01X1146283Y871757D02*
X1596192Y914387D01*
G01X1132278Y873082D02*
X1146212D01*
G01X1132278Y871757D02*
X1146283D01*
G01X1129796Y870600D02*
G02X1132278Y873082I2482J0D01*
G01X1131121Y870600D02*
G02X1132278Y871757I1157J0D01*
G01X1129796Y869600D02*
Y870600D01*
G01X1131121Y869600D02*
Y870600D01*
G01X1146283Y871757D02*
X1596192Y914387D01*
G01X1146212Y873082D02*
X1595889Y915690D01*
G01X1132278Y871757D02*
X1146283D01*
G01X1132278Y873082D02*
X1146212D01*
G01X1131121Y870600D02*
G02X1132278Y871757I1157J0D01*
G01X1129796Y870600D02*
G02X1132278Y873082I2482J0D01*
G01X1131121Y869600D02*
Y870600D01*
G01X1129796Y869600D02*
Y870600D01*
G01Y938200D02*
G02X1128457Y936861I-1339J0D01*
G01X1131121Y938200D02*
G02X1128457Y935536I-2664J0D01*
G01X1129796Y939100D02*
Y938200D01*
G01X1131121Y939100D02*
Y938200D01*
G01D02*
G02X1128457Y935536I-2664J0D01*
G01X1129796Y938200D02*
G02X1128457Y936861I-1339J0D01*
G01X1131121Y939100D02*
Y938200D01*
G01X1129796Y939100D02*
Y938200D01*
G01X1125859Y931113D02*
G02X1124520Y929774I-1339J0D01*
G01X1127184Y931113D02*
G02X1124520Y928449I-2664J0D01*
G01X1125859Y932013D02*
Y931113D01*
G01X1127184Y932013D02*
Y931113D01*
G01D02*
G02X1124520Y928449I-2664J0D01*
G01X1125859Y931113D02*
G02X1124520Y929774I-1339J0D01*
G01X1127184Y932013D02*
Y931113D01*
G01X1125859Y932013D02*
Y931113D01*
G01X1129796Y924027D02*
G02X1128457Y922688I-1339J0D01*
G01X1131121Y924027D02*
G02X1128457Y921363I-2664J0D01*
G01X1129796Y924927D02*
Y924027D01*
G01X1131121Y924927D02*
Y924027D01*
G01D02*
G02X1128457Y921363I-2664J0D01*
G01X1129796Y924027D02*
G02X1128457Y922688I-1339J0D01*
G01X1131121Y924927D02*
Y924027D01*
G01X1129796Y924927D02*
Y924027D01*
G01X1125859Y916940D02*
G02X1124520Y915601I-1339J0D01*
G01X1127184Y916940D02*
G02X1124520Y914276I-2664J0D01*
G01X1125859Y917840D02*
Y916940D01*
G01X1127184Y917840D02*
Y916940D01*
G01D02*
G02X1124520Y914276I-2664J0D01*
G01X1125859Y916940D02*
G02X1124520Y915601I-1339J0D01*
G01X1127184Y917840D02*
Y916940D01*
G01X1125859Y917840D02*
Y916940D01*
G01X1129796Y909854D02*
G02X1128457Y908515I-1339J0D01*
G01X1131121Y909854D02*
G02X1128457Y907190I-2664J0D01*
G01X1129796Y910754D02*
Y909854D01*
G01X1131121Y910754D02*
Y909854D01*
G01D02*
G02X1128457Y907190I-2664J0D01*
G01X1129796Y909854D02*
G02X1128457Y908515I-1339J0D01*
G01X1131121Y910754D02*
Y909854D01*
G01X1129796Y910754D02*
Y909854D01*
G01X1125859Y902767D02*
G02X1124520Y901428I-1339J0D01*
G01X1127184Y902767D02*
G02X1124520Y900103I-2664J0D01*
G01X1125859Y903667D02*
Y902767D01*
G01X1127184Y903667D02*
Y902767D01*
G01D02*
G02X1124520Y900103I-2664J0D01*
G01X1125859Y902767D02*
G02X1124520Y901428I-1339J0D01*
G01X1127184Y903667D02*
Y902767D01*
G01X1125859Y903667D02*
Y902767D01*
G01X1183836Y636531D02*
X1272237Y155512D01*
G01X1185092Y637031D02*
X1265255Y200837D01*
G01X1183836Y636531D02*
X1272237Y155512D01*
G01X1183836Y636531D02*
X1272237Y155512D01*
G01X1183836Y636531D02*
X1272237Y155512D01*
G01X1185092Y637031D02*
X1265255Y200837D01*
G01X1183836Y636531D02*
X1272237Y155512D01*
G01X1225552Y489063D02*
X1347692Y300991D01*
G01X1226797Y489579D02*
X1308608Y363606D01*
G01X1225552Y489063D02*
X1347692Y300991D01*
G01X1225552Y489063D02*
X1347692Y300991D01*
G01X1225552Y489063D02*
X1347692Y300991D01*
G01X1226797Y489579D02*
X1308608Y363606D01*
G01X1225552Y489063D02*
X1347692Y300991D01*
G01X1228233Y641595D02*
X1247113Y552775D01*
G01X1228233Y641595D02*
X1247113Y552775D01*
G01X1218450Y648130D02*
X1247919Y509464D01*
G01X1217205Y647614D02*
X1246623Y509188D01*
G01X1218450Y648130D02*
X1247919Y509464D01*
G01X1218450Y648130D02*
X1247919Y509464D01*
G01X1217205Y647614D02*
X1246623Y509188D01*
G01X1237484Y507519D02*
X1422651Y232998D01*
G01X1238727Y508047D02*
X1423604Y233957D01*
G01X1207242Y649799D02*
X1237484Y507519D01*
G01X1208487Y650315D02*
X1238727Y508047D01*
G01D02*
X1423604Y233957D01*
G01X1237484Y507519D02*
X1422651Y232998D01*
G01X1208487Y650315D02*
X1238727Y508047D01*
G01X1207242Y649799D02*
X1237484Y507519D01*
G01X1230854Y505121D02*
X1519985Y76471D01*
G01X1232097Y505648D02*
X1485622Y129786D01*
G01X1200239Y649173D02*
X1230854Y505121D01*
G01X1201484Y649689D02*
X1232097Y505648D01*
G01X1230854Y505121D02*
X1519985Y76471D01*
G01X1230854Y505121D02*
X1519985Y76471D01*
G01X1230854Y505121D02*
X1519985Y76471D01*
G01X1232097Y505648D02*
X1485622Y129786D01*
G01X1230854Y505121D02*
X1519985Y76471D01*
G01X1201484Y649689D02*
X1232097Y505648D01*
G01X1200239Y649173D02*
X1230854Y505121D01*
G01X1194809Y633721D02*
X1225552Y489063D01*
G01X1196054Y634237D02*
X1226797Y489579D01*
G01X1196054Y634237D02*
X1226797Y489579D01*
G01X1194809Y633721D02*
X1225552Y489063D01*
G01X1238294Y639352D02*
X1272237Y533196D01*
G01X1239507Y639912D02*
X1253778Y595279D01*
G01X1162391Y761626D02*
X1238294Y639352D01*
G01X1163325Y762636D02*
X1239507Y639912D01*
G01X1238294Y639352D02*
X1272237Y533196D01*
G01X1238294Y639352D02*
X1272237Y533196D01*
G01X1238294Y639352D02*
X1272237Y533196D01*
G01X1239507Y639912D02*
X1253778Y595279D01*
G01X1238294Y639352D02*
X1272237Y533196D01*
G01X1163325Y762636D02*
X1239507Y639912D01*
G01X1162391Y761626D02*
X1238294Y639352D01*
G01X1229478Y642111D02*
X1248382Y553182D01*
G01X1199718Y685507D02*
X1228233Y641595D01*
G01X1200676Y686465D02*
X1229478Y642111D01*
G01D02*
X1248382Y553182D01*
G01X1200676Y686465D02*
X1229478Y642111D01*
G01X1199718Y685507D02*
X1228233Y641595D01*
G01X1209107Y660084D02*
X1217205Y647614D01*
G01X1196574Y681817D02*
X1218450Y648130D01*
G01X1206409Y664237D02*
X1209106Y660083D01*
G01X1196574Y681817D02*
X1218450Y648130D01*
G01X1195616Y680859D02*
X1206409Y664237D01*
G01X1196574Y681817D02*
X1218450Y648130D01*
G01X1196574Y681817D02*
X1218450Y648130D01*
G01X1209107Y660084D02*
X1217205Y647614D01*
G01X1206409Y664237D02*
X1209106Y660083D01*
G01X1195616Y680859D02*
X1206409Y664237D01*
G01X1188524Y678623D02*
X1207242Y649799D01*
G01X1189483Y679581D02*
X1208487Y650315D01*
G01X1189483Y679581D02*
X1208487Y650315D01*
G01X1188524Y678623D02*
X1207242Y649799D01*
G01X1184215Y673850D02*
X1200239Y649173D01*
G01X1185173Y674808D02*
X1201484Y649689D01*
G01X1185173Y674808D02*
X1201484Y649689D01*
G01X1184215Y673850D02*
X1200239Y649173D01*
G01X1169876Y672108D02*
X1194809Y633721D01*
G01X1170834Y673066D02*
X1196054Y634237D01*
G01X1170834Y673066D02*
X1196054Y634237D01*
G01X1169876Y672108D02*
X1194809Y633721D01*
G01X1161204Y671380D02*
X1183836Y636531D01*
G01X1162162Y672338D02*
X1185092Y637031D01*
G01X1162162Y672338D02*
X1185092Y637031D01*
G01X1161204Y671380D02*
X1183836Y636531D01*
G01X1234920Y742842D02*
X1396450Y524836D01*
G01X1235862Y743797D02*
X1350739Y588755D01*
G01X1227390Y748266D02*
X1234920Y742842D01*
G01X1228012Y749451D02*
X1235862Y743797D01*
G01X1234920Y742842D02*
X1396450Y524836D01*
G01X1234920Y742842D02*
X1396450Y524836D01*
G01X1234920Y742842D02*
X1396450Y524836D01*
G01X1235862Y743797D02*
X1350739Y588755D01*
G01X1234920Y742842D02*
X1396450Y524836D01*
G01X1228012Y749451D02*
X1235862Y743797D01*
G01X1227390Y748266D02*
X1234920Y742842D01*
G01X1188525Y678623D02*
X1188524D01*
G01X1188525D02*
X1188524D01*
G01X1178409Y807977D02*
X1253435Y797925D01*
G01X1216097Y804265D02*
X1253661Y799232D01*
G01X1178498Y809302D02*
X1216097Y804265D01*
G01D02*
X1253661Y799232D01*
G01X1178409Y807977D02*
X1253435Y797925D01*
G01X1178498Y809302D02*
X1216097Y804265D01*
G01X1178409Y807977D02*
X1253435Y797925D01*
G01X1177189Y800890D02*
X1253948Y791697D01*
G01X1177269Y802215D02*
X1254165Y793006D01*
G01X1177269Y802215D02*
X1254165Y793006D01*
G01X1177189Y800890D02*
X1253948Y791697D01*
G01X1201816Y907928D02*
X1259542Y922825D01*
G01X1201816Y907928D02*
X1259542Y922825D01*
G01X1149081Y865995D02*
X1728502Y909534D01*
G01X1149140Y864670D02*
X1728728Y908222D01*
G01X1149140Y864670D02*
X1728728Y908222D01*
G01X1149081Y865995D02*
X1728502Y909534D01*
G01X1234405Y957613D02*
X1266826Y978668D01*
G01X1230673Y955190D02*
X1231868Y955966D01*
G01X1226940Y952766D02*
X1228136Y953542D01*
G01X1234405Y957613D02*
X1266826Y978668D01*
G01X1230673Y955190D02*
X1231868Y955966D01*
G01X1226940Y952766D02*
X1228136Y953542D01*
G01X1272237Y155512D02*
Y69237D01*
G01X1273562Y155633D02*
Y69238D01*
G01Y155633D02*
Y69238D01*
G01X1272237Y155512D02*
Y69237D01*
G01X1267410Y189108D02*
X1273562Y155633D01*
G01X1267410Y189108D02*
X1273562Y155633D01*
G01X1266606Y193485D02*
X1266864Y192084D01*
G01X1265802Y197862D02*
X1266059Y196460D01*
G01X1266606Y193485D02*
X1266864Y192084D01*
G01X1265802Y197862D02*
X1266059Y196460D01*
G01X1315103Y353605D02*
X1348937Y301507D01*
G01X1312679Y357337D02*
X1313456Y356142D01*
G01X1310256Y361069D02*
X1311032Y359874D01*
G01X1315103Y353605D02*
X1348937Y301507D01*
G01X1312679Y357337D02*
X1313456Y356142D01*
G01X1310256Y361069D02*
X1311032Y359874D01*
G01X1266098Y509183D02*
X1383868Y432704D01*
G01X1267154Y510078D02*
X1374388Y440442D01*
G01X1266098Y509183D02*
X1383868Y432704D01*
G01X1266098Y509183D02*
X1383868Y432704D01*
G01X1267154Y510078D02*
X1374388Y440442D01*
G01X1266098Y509183D02*
X1383868Y432704D01*
G01X1250457Y504043D02*
X1572745Y294747D01*
G01X1251366Y505033D02*
X1573705Y295705D01*
G01X1251366Y505033D02*
X1573705Y295705D01*
G01X1250457Y504043D02*
X1572745Y294747D01*
G01X1272237Y533196D02*
Y522037D01*
G01X1273562Y533403D02*
Y522038D01*
G01X1257410Y583920D02*
X1273562Y533403D01*
G01D02*
Y522038D01*
G01X1272237Y533196D02*
Y522037D01*
G01X1257410Y583920D02*
X1273562Y533403D01*
G01X1247113Y552775D02*
X1266098Y509183D01*
G01X1248382Y553182D02*
X1267154Y510078D01*
G01X1248382Y553182D02*
X1267154Y510078D01*
G01X1247113Y552775D02*
X1266098Y509183D01*
G01X1249458Y505327D02*
X1250457Y504043D01*
G01X1249643Y507249D02*
X1251366Y505033D01*
G01X1246686Y508891D02*
X1249458Y505327D01*
G01X1249643Y507249D02*
X1251366Y505033D01*
G01X1247919Y509464D02*
X1249643Y507249D01*
G01X1246623Y509188D02*
X1246686Y508891D01*
G01X1249643Y507249D02*
X1251366Y505033D01*
G01X1249458Y505327D02*
X1250457Y504043D01*
G01X1246686Y508891D02*
X1249458Y505327D01*
G01X1247919Y509464D02*
X1249643Y507249D01*
G01X1246686Y508891D02*
X1249458Y505327D01*
G01X1246623Y509188D02*
X1246686Y508891D01*
G01X1256054Y588159D02*
X1256488Y586802D01*
G01X1254699Y592398D02*
X1255133Y591040D01*
G01X1256054Y588159D02*
X1256488Y586802D01*
G01X1254699Y592398D02*
X1255133Y591040D01*
G01X1324514Y763151D02*
X1614634Y574741D01*
G01X1325002Y764415D02*
X1593597Y589984D01*
G01X1324514Y763151D02*
X1614634Y574741D01*
G01X1324514Y763151D02*
X1614634Y574741D01*
G01X1324514Y763151D02*
X1614634Y574741D01*
G01X1325002Y764415D02*
X1593597Y589984D01*
G01X1324514Y763151D02*
X1614634Y574741D01*
G01X1315250Y758684D02*
X1413037Y695182D01*
G01X1315740Y759946D02*
X1413995Y696140D01*
G01X1315740Y759946D02*
X1413995Y696140D01*
G01X1315250Y758684D02*
X1413037Y695182D01*
G01X1253435Y797925D02*
X1383594Y770257D01*
G01X1253661Y799232D02*
X1384104Y771504D01*
G01X1253661Y799232D02*
X1384104Y771504D01*
G01X1253435Y797925D02*
X1383594Y770257D01*
G01X1253948Y791697D02*
X1373745Y766234D01*
G01X1254165Y793006D02*
X1374261Y767479D01*
G01X1254165Y793006D02*
X1374261Y767479D01*
G01X1253948Y791697D02*
X1373745Y766234D01*
G01X1327616Y904169D02*
X1508598Y928170D01*
G01X1327616Y904169D02*
X1508598Y928170D01*
G01X1259102Y924080D02*
X1386005Y979993D01*
G01X1259542Y922825D02*
X1360225Y967186D01*
G01X1259102Y924080D02*
X1386005Y979993D01*
G01X1259102Y924080D02*
X1386005Y979993D01*
G01X1259102Y924080D02*
X1386005Y979993D01*
G01X1259542Y922825D02*
X1360225Y967186D01*
G01X1259102Y924080D02*
X1386005Y979993D01*
G01X1266433D02*
X1273500D01*
G01X1266826Y978668D02*
X1273500D01*
G01X1266826D02*
X1273500D01*
G01X1266433Y979993D02*
X1273500D01*
G01X1396450Y71700D02*
Y69250D01*
G01X1397775Y71840D02*
Y69251D01*
G01X1347692Y300991D02*
X1396450Y71700D01*
G01X1356663Y265176D02*
X1397775Y71840D01*
G01D02*
Y69251D01*
G01X1396450Y71700D02*
Y69250D01*
G01X1356663Y265176D02*
X1397775Y71840D01*
G01X1347692Y300991D02*
X1396450Y71700D01*
G01X1347692Y300991D02*
X1396450Y71700D01*
G01X1422651Y232998D02*
X1631398Y94128D01*
G01X1423604Y233957D02*
X1484163Y193670D01*
G01X1422651Y232998D02*
X1631398Y94128D01*
G01X1422651Y232998D02*
X1631398Y94128D01*
G01X1422651Y232998D02*
X1631398Y94128D01*
G01X1423604Y233957D02*
X1484163Y193670D01*
G01X1422651Y232998D02*
X1631398Y94128D01*
G01X1348937Y301507D02*
X1356663Y265176D01*
G01X1348937Y301507D02*
X1356663Y265176D01*
G01X1383867Y432704D02*
X1571494Y310862D01*
G01X1384590Y433816D02*
X1572452Y311820D01*
G01X1383868Y432704D02*
X1383867D01*
G01X1384590Y433816D02*
X1572452Y311820D01*
G01X1380791Y436284D02*
X1381986Y435508D01*
G01X1376992Y438751D02*
X1378187Y437975D01*
G01X1384590Y433816D02*
X1572452Y311820D01*
G01X1383867Y432704D02*
X1571494Y310862D01*
G01X1383868Y432704D02*
X1383867D01*
G01X1380791Y436284D02*
X1381986Y435508D01*
G01X1376992Y438751D02*
X1378187Y437975D01*
G01X1396450Y524836D02*
Y522050D01*
G01X1397775Y525274D02*
Y522051D01*
G01X1357839Y579174D02*
X1397775Y525274D01*
G01D02*
Y522051D01*
G01X1396450Y524836D02*
Y522050D01*
G01X1357839Y579174D02*
X1397775Y525274D01*
G01X1413037Y695182D02*
X1520436Y529743D01*
G01X1413995Y696140D02*
X1444909Y648520D01*
G01X1413037Y695182D02*
X1520436Y529743D01*
G01X1413037Y695182D02*
X1520436Y529743D01*
G01X1413037Y695182D02*
X1520436Y529743D01*
G01X1413995Y696140D02*
X1444909Y648520D01*
G01X1413037Y695182D02*
X1520436Y529743D01*
G01X1355190Y582749D02*
X1356038Y581604D01*
G01X1352540Y586325D02*
X1353389Y585180D01*
G01X1355190Y582749D02*
X1356038Y581604D01*
G01X1352540Y586325D02*
X1353389Y585180D01*
G01X1383594Y770257D02*
X1493096Y700436D01*
G01X1384104Y771504D02*
X1493814Y701551D01*
G01X1384104Y771504D02*
X1493814Y701551D01*
G01X1383594Y770257D02*
X1493096Y700436D01*
G01X1373745Y766234D02*
X1631229Y599022D01*
G01X1374261Y767479D02*
X1450405Y718031D01*
G01X1373745Y766234D02*
X1631229Y599022D01*
G01X1373745Y766234D02*
X1631229Y599022D01*
G01X1373745Y766234D02*
X1631229Y599022D01*
G01X1374261Y767479D02*
X1450405Y718031D01*
G01X1373745Y766234D02*
X1631229Y599022D01*
G01X1403426Y935472D02*
X1513534Y979993D01*
G01X1403801Y934194D02*
X1513792Y978668D01*
G01X1394480Y933784D02*
X1403426Y935472D01*
G01X1367887Y927416D02*
X1403801Y934194D01*
G01X1363436Y926576D02*
X1364836Y926840D01*
G01X1359063Y925751D02*
X1360463Y926015D01*
G01X1403801Y934194D02*
X1513792Y978668D01*
G01X1403426Y935472D02*
X1513534Y979993D01*
G01X1367887Y927416D02*
X1403801Y934194D01*
G01X1394480Y933784D02*
X1403426Y935472D01*
G01X1363436Y926576D02*
X1364836Y926840D01*
G01X1359063Y925751D02*
X1360463Y926015D01*
G01X1386005Y979993D02*
X1397713D01*
G01X1386284Y978668D02*
X1397713D01*
G01X1371137Y971994D02*
X1386284Y978668D01*
G01X1367065Y970199D02*
X1368369Y970774D01*
G01X1362993Y968405D02*
X1364297Y968980D01*
G01X1386284Y978668D02*
X1397713D01*
G01X1386005Y979993D02*
X1397713D01*
G01X1371137Y971994D02*
X1386284Y978668D01*
G01X1367065Y970199D02*
X1368369Y970774D01*
G01X1362993Y968405D02*
X1364297Y968980D01*
G01X1520662Y72990D02*
Y69200D01*
G01X1521987Y73118D02*
Y69201D01*
G01X1519985Y76471D02*
X1520662Y72990D01*
G01X1521235Y76988D02*
X1521987Y73118D01*
G01X1492291Y119900D02*
X1521235Y76988D01*
G01X1521987Y73118D02*
Y69201D01*
G01X1520662Y72990D02*
Y69200D01*
G01X1521235Y76988D02*
X1521987Y73118D01*
G01X1519985Y76471D02*
X1520662Y72990D01*
G01X1492291Y119900D02*
X1521235Y76988D01*
G01X1494091Y187065D02*
X1632361Y95080D01*
G01X1494091Y187065D02*
X1632361Y95080D01*
G01X1489802Y123589D02*
X1490599Y122407D01*
G01X1487314Y127278D02*
X1488111Y126097D01*
G01X1489802Y123589D02*
X1490599Y122407D01*
G01X1487314Y127278D02*
X1488111Y126097D01*
G01X1490386Y189530D02*
X1491573Y188740D01*
G01X1486681Y191995D02*
X1487868Y191205D01*
G01X1490386Y189530D02*
X1491573Y188740D01*
G01X1486681Y191995D02*
X1487868Y191205D01*
G01X1520662Y528683D02*
Y521962D01*
G01X1521987Y528823D02*
Y521963D01*
G01X1520436Y529743D02*
X1520662Y528683D01*
G01X1521681Y530259D02*
X1521987Y528823D01*
G01X1451403Y638517D02*
X1521681Y530259D01*
G01X1521987Y528823D02*
Y521963D01*
G01X1520662Y528683D02*
Y521962D01*
G01X1521681Y530259D02*
X1521987Y528823D01*
G01X1520436Y529743D02*
X1520662Y528683D01*
G01X1451403Y638517D02*
X1521681Y530259D01*
G01X1448980Y642250D02*
X1449756Y641055D01*
G01X1446557Y645983D02*
X1447333Y644787D01*
G01X1448980Y642250D02*
X1449756Y641055D01*
G01X1446557Y645983D02*
X1447333Y644787D01*
G01X1493096Y700436D02*
X1592375Y635967D01*
G01X1493814Y701551D02*
X1592891Y637212D01*
G01X1493814Y701551D02*
X1592891Y637212D01*
G01X1493096Y700436D02*
X1592375Y635967D01*
G01X1460406Y711536D02*
X1631745Y600267D01*
G01X1456674Y713960D02*
X1457869Y713183D01*
G01X1452942Y716383D02*
X1454137Y715607D01*
G01X1460406Y711536D02*
X1631745Y600267D01*
G01X1456674Y713960D02*
X1457869Y713183D01*
G01X1452942Y716383D02*
X1454137Y715607D01*
G01X1508598Y928170D02*
X1643337Y979993D01*
G01X1508928Y926876D02*
X1602536Y962880D01*
G01X1508598Y928170D02*
X1643337Y979993D01*
G01X1508598Y928170D02*
X1643337Y979993D01*
G01X1508598Y928170D02*
X1643337Y979993D01*
G01X1508928Y926876D02*
X1602536Y962880D01*
G01X1508598Y928170D02*
X1643337Y979993D01*
G01X1513534D02*
X1521600D01*
G01X1513792Y978668D02*
X1521601D01*
G01X1513792D02*
X1521601D01*
G01X1513534Y979993D02*
X1521600D01*
G01X1571494Y310862D02*
X1640542Y204524D01*
G01X1572452Y311820D02*
X1641500Y205482D01*
G01X1572452Y311820D02*
X1641500Y205482D01*
G01X1571494Y310862D02*
X1640542Y204524D01*
G01X1572745Y294747D02*
X1675991Y135099D01*
G01X1573705Y295705D02*
X1676951Y136057D01*
G01X1573705Y295705D02*
X1676951Y136057D01*
G01X1572745Y294747D02*
X1675991Y135099D01*
G01X1614634Y574741D02*
X1644875Y528146D01*
G01X1615592Y575699D02*
X1646200Y528539D01*
G01X1615592Y575699D02*
X1646200Y528539D01*
G01X1614634Y574741D02*
X1644875Y528146D01*
G01X1592375Y635967D02*
X1821102Y587349D01*
G01X1612619Y633019D02*
X1821618Y588594D01*
G01X1608266Y633944D02*
X1609660Y633648D01*
G01X1603914Y634869D02*
X1605308Y634573D01*
G01X1592891Y637212D02*
X1600955Y635498D01*
G01X1612619Y633019D02*
X1821618Y588594D01*
G01X1592375Y635967D02*
X1821102Y587349D01*
G01X1608266Y633944D02*
X1609660Y633648D01*
G01X1592375Y635967D02*
X1821102Y587349D01*
G01X1603914Y634869D02*
X1605308Y634573D01*
G01X1592375Y635967D02*
X1821102Y587349D01*
G01X1592891Y637212D02*
X1600955Y635498D01*
G01X1592375Y635967D02*
X1821102Y587349D01*
G01X1603598Y583489D02*
X1615592Y575699D01*
G01X1599866Y585912D02*
X1601061Y585136D01*
G01X1596134Y588336D02*
X1597329Y587560D01*
G01X1603598Y583489D02*
X1615592Y575699D01*
G01X1599866Y585912D02*
X1601061Y585136D01*
G01X1596134Y588336D02*
X1597329Y587560D01*
G01X1595889Y915690D02*
X1741934Y970635D01*
G01X1596192Y914387D02*
X1731240Y965195D01*
G01X1595889Y915690D02*
X1741934Y970635D01*
G01X1595889Y915690D02*
X1741934Y970635D01*
G01X1596192Y914387D02*
X1731240Y965195D01*
G01X1595889Y915690D02*
X1741934Y970635D01*
G01X1613665Y967160D02*
X1643584Y978668D01*
G01X1609512Y965563D02*
X1610842Y966075D01*
G01X1605359Y963965D02*
X1606689Y964477D01*
G01X1613665Y967160D02*
X1643584Y978668D01*
G01X1609512Y965563D02*
X1610842Y966075D01*
G01X1605359Y963965D02*
X1606689Y964477D01*
G01X1644875Y72147D02*
Y69200D01*
G01X1646200Y72287D02*
Y69201D01*
G01X1644488Y73967D02*
X1644875Y72147D01*
G01X1645733Y74483D02*
X1646200Y72287D01*
G01X1631398Y94128D02*
X1644488Y73967D01*
G01X1632361Y95080D02*
X1645733Y74483D01*
G01X1646200Y72287D02*
Y69201D01*
G01X1644875Y72147D02*
Y69200D01*
G01X1645733Y74483D02*
X1646200Y72287D01*
G01X1644488Y73967D02*
X1644875Y72147D01*
G01X1632361Y95080D02*
X1645733Y74483D01*
G01X1631398Y94128D02*
X1644488Y73967D01*
G01X1705617Y162265D02*
X1846404Y132338D01*
G01X1706133Y163510D02*
X1846920Y133583D01*
G01X1640542Y204524D02*
X1705617Y162265D01*
G01X1641500Y205482D02*
X1706133Y163510D01*
G01D02*
X1846920Y133583D01*
G01X1705617Y162265D02*
X1846404Y132338D01*
G01X1641500Y205482D02*
X1706133Y163510D01*
G01X1640542Y204524D02*
X1705617Y162265D01*
G01X1714300Y110221D02*
X1766455Y76352D01*
G01X1715023Y111333D02*
X1767415Y77309D01*
G01X1714301Y110221D02*
X1714300D01*
G01X1715023Y111333D02*
X1767415Y77309D01*
G01X1675991Y135099D02*
X1714301Y110221D01*
G01X1711291Y113756D02*
X1712486Y112980D01*
G01X1707559Y116180D02*
X1708754Y115404D01*
G01X1676951Y136057D02*
X1705022Y117828D01*
G01X1715023Y111333D02*
X1767415Y77309D01*
G01X1714300Y110221D02*
X1766455Y76352D01*
G01X1714301Y110221D02*
X1714300D01*
G01X1711291Y113756D02*
X1712486Y112980D01*
G01X1675991Y135099D02*
X1714301Y110221D01*
G01X1707559Y116180D02*
X1708754Y115404D01*
G01X1675991Y135099D02*
X1714301Y110221D01*
G01X1676951Y136057D02*
X1705022Y117828D01*
G01X1675991Y135099D02*
X1714301Y110221D01*
G01X1685509Y587484D02*
X1759105Y539695D01*
G01X1686025Y588729D02*
X1760063Y540653D01*
G01X1686025Y588729D02*
X1760063Y540653D01*
G01X1685509Y587484D02*
X1759105Y539695D01*
G01X1644875Y528146D02*
Y522200D01*
G01X1646200Y528539D02*
Y522200D01*
G01Y528539D02*
Y522200D01*
G01X1644875Y528146D02*
Y522200D01*
G01X1631229Y599022D02*
X1685509Y587484D01*
G01X1631745Y600267D02*
X1686025Y588729D01*
G01X1631745Y600267D02*
X1686025Y588729D01*
G01X1631229Y599022D02*
X1685509Y587484D01*
G01X1643337Y979993D02*
X1646138D01*
G01X1643584Y978668D02*
X1646138D01*
G01X1643584D02*
X1646138D01*
G01X1643337Y979993D02*
X1646138D01*
G01X1769087Y72268D02*
Y69200D01*
G01X1770412Y72658D02*
Y69201D01*
G01X1766455Y76352D02*
X1769087Y72268D01*
G01X1767415Y77309D02*
X1770412Y72658D01*
G01D02*
Y69201D01*
G01X1769087Y72268D02*
Y69200D01*
G01X1767415Y77309D02*
X1770412Y72658D01*
G01X1766455Y76352D02*
X1769087Y72268D01*
G01Y524332D02*
Y521987D01*
G01X1770412Y524725D02*
Y521988D01*
G01X1759105Y539695D02*
X1769087Y524332D01*
G01X1760063Y540653D02*
X1770412Y524725D01*
G01D02*
Y521988D01*
G01X1769087Y524332D02*
Y521987D01*
G01X1760063Y540653D02*
X1770412Y524725D01*
G01X1759105Y539695D02*
X1769087Y524332D01*
G01X1782799Y924364D02*
X1839362Y941351D01*
G01X1783164Y923090D02*
X1827103Y936285D01*
G01X1755652Y916950D02*
X1782799Y924364D01*
G01X1756001Y915671D02*
X1783164Y923090D01*
G01X1732591Y910651D02*
X1755652Y916950D01*
G01X1744472Y912522D02*
X1756001Y915671D01*
G01X1728728Y908222D02*
X1744472Y912522D01*
G01X1728502Y909534D02*
X1732591Y910651D01*
G01X1728728Y908222D02*
X1744472Y912522D01*
G01X1782799Y924364D02*
X1839362Y941351D01*
G01X1782799Y924364D02*
X1839362Y941351D01*
G01X1782799Y924364D02*
X1839362Y941351D01*
G01X1783164Y923090D02*
X1827103Y936285D01*
G01X1782799Y924364D02*
X1839362Y941351D01*
G01X1756001Y915671D02*
X1783164Y923090D01*
G01X1755652Y916950D02*
X1782799Y924364D01*
G01X1744472Y912522D02*
X1756001Y915671D01*
G01X1732591Y910651D02*
X1755652Y916950D01*
G01X1728728Y908222D02*
X1744472Y912522D01*
G01X1732591Y910651D02*
X1755652Y916950D01*
G01X1728502Y909534D02*
X1732591Y910651D01*
G01X1766808Y979993D02*
X1770350D01*
G01X1767049Y978668D02*
X1770350D01*
G01X1741933Y970636D02*
X1766808Y979993D01*
G01X1742401Y969395D02*
X1767049Y978668D01*
G01X1738236Y967827D02*
X1739570Y968329D01*
G01X1734071Y966260D02*
X1735405Y966762D01*
G01X1767049Y978668D02*
X1770350D01*
G01X1766808Y979993D02*
X1770350D01*
G01X1742401Y969395D02*
X1767049Y978668D01*
G01X1741933Y970636D02*
X1766808Y979993D01*
G01X1738236Y967827D02*
X1739570Y968329D01*
G01X1734071Y966260D02*
X1735405Y966762D01*
G01X1893300Y71812D02*
Y69200D01*
G01X1894625Y71952D02*
Y69275D01*
G01X1890710Y83994D02*
X1893300Y71812D01*
G01X1891955Y84510D02*
X1894625Y71952D01*
G01X1868726Y117842D02*
X1890710Y83994D01*
G01X1891822Y84715D02*
X1891955Y84510D01*
G01X1869684Y118800D02*
X1891822Y84715D01*
G01X1894625Y71952D02*
Y69275D01*
G01X1893300Y71812D02*
Y69200D01*
G01X1891955Y84510D02*
X1894625Y71952D01*
G01X1890710Y83994D02*
X1893300Y71812D01*
G01X1891822Y84715D02*
X1891955Y84510D01*
G01X1868726Y117842D02*
X1890710Y83994D01*
G01X1869684Y118800D02*
X1891822Y84715D01*
G01X1868726Y117842D02*
X1890710Y83994D01*
G01X1846404Y132338D02*
X1868726Y117842D01*
G01X1846920Y133583D02*
X1869684Y118800D01*
G01X1846920Y133583D02*
X1869684Y118800D01*
G01X1846404Y132338D02*
X1868726Y117842D01*
G01X1893300Y531851D02*
Y521900D01*
G01X1894625Y532244D02*
Y521901D01*
G01X1883627Y546746D02*
X1893300Y531851D01*
G01X1884585Y547704D02*
X1894625Y532244D01*
G01X1821102Y587349D02*
X1883627Y546746D01*
G01X1821618Y588594D02*
X1884585Y547704D01*
G01X1894625Y532244D02*
Y521901D01*
G01X1893300Y531851D02*
Y521900D01*
G01X1884585Y547704D02*
X1894625Y532244D01*
G01X1883627Y546746D02*
X1893300Y531851D01*
G01X1821618Y588594D02*
X1884585Y547704D01*
G01X1821102Y587349D02*
X1883627Y546746D01*
G01X1839362Y941351D02*
X1860114Y953228D01*
G01X1839889Y940125D02*
X1861017Y952217D01*
G01X1838524Y939715D02*
X1839889Y940125D01*
G01X1834262Y938435D02*
X1835627Y938845D01*
G01X1830000Y937155D02*
X1831365Y937565D01*
G01X1839889Y940125D02*
X1861017Y952217D01*
G01X1839362Y941351D02*
X1860114Y953228D01*
G01X1838524Y939715D02*
X1839889Y940125D01*
G01X1834262Y938435D02*
X1835627Y938845D01*
G01X1830000Y937155D02*
X1831365Y937565D01*
G01X1886613Y979993D02*
X1894300D01*
G01X1886930Y978668D02*
X1894301D01*
G01X1881136Y977217D02*
X1886613Y979993D01*
G01X1881735Y976035D02*
X1886930Y978668D01*
G01X1875656Y974439D02*
X1881136Y977217D01*
G01X1876538Y973400D02*
X1881735Y976035D01*
G01X1860114Y953228D02*
X1875656Y974439D01*
G01X1861017Y952217D02*
X1876538Y973400D01*
G01X1886930Y978668D02*
X1894301D01*
G01X1886613Y979993D02*
X1894300D01*
G01X1881735Y976035D02*
X1886930Y978668D01*
G01X1881136Y977217D02*
X1886613Y979993D01*
G01X1876538Y973400D02*
X1881735Y976035D01*
G01X1875656Y974439D02*
X1881136Y977217D01*
G01X1861017Y952217D02*
X1876538Y973400D01*
G01X1860114Y953228D02*
X1875656Y974439D01*
M02*
